FILE_TYPE = MACRO_DRAWING;
SET COLOR_WIRE YELLOW;
SET COLOR_PROP MONO;
SET COLOR_DOT WHITE;
SET COLOR_ARC YELLOW;
SET COLOR_BODY GREEN;
SET COLOR_NOTE MONO;
SET PROP_DISPLAY VALUE;
SET PAGE_NUMBER P187;
FORCEADD OFFPAGE..1
(-3050 4025);
FORCEPROP 2 LAST $XR0 106 
J 0
(-3302 4025);
DISPLAY 0.638298 (-3302 4025);
PAINT MONO (-3302 4025);
FORCEPROP 2 LAST PATH I100
J 0
(-3000 4100);
DISPLAY 1.021277 (-3000 4100);
PAINT ORANGE (-3000 4100);
DISPLAY INVISIBLE (-3000 4100);
FORCEPROP 1 LAST COMMENT_BODY TRUE
J 0
(-2925 3925);
DISPLAY 0.872340 (-2925 3925);
PAINT GREEN (-2925 3925);
DISPLAY INVISIBLE (-2925 3925);
FORCEPROP 1 LAST OFFPAGE TRUE
J 0
(-2725 3900);
DISPLAY 0.872340 (-2725 3900);
PAINT GREEN (-2725 3900);
DISPLAY INVISIBLE (-2725 3900);
FORCEPROP 2 LAST CDS_LIB mstr_standard
J 0
(-3050 4025);
PAINT ORANGE (-3050 4025);
DISPLAY INVISIBLE (-3050 4025);
FORCEADD TAP..1
(1550 3300);
FORCEPROP 3 LASTPIN (1500 3300) SIG_NAME P3E_CPU0_PE3_OCP_RXP<4>
J 0
(1510 3310);
DISPLAY 0.659574 (1510 3310);
PAINT MONO (1510 3310);
DISPLAY INVISIBLE (1510 3310);
FORCEPROP 1 LASTPIN (1500 3300) BN 4
J 0
(1488 3308);
DISPLAY 0.617021 (1488 3308);
PAINT GREEN (1488 3308);
FORCEPROP 1 LAST PATH I111
J 0
(1548 3300);
DISPLAY 0.872340 (1548 3300);
PAINT GREEN (1548 3300);
DISPLAY INVISIBLE (1548 3300);
FORCEPROP 1 LAST HDL_TAP TRUE
J 0
(1875 3175);
DISPLAY 0.872340 (1875 3175);
PAINT ORANGE (1875 3175);
DISPLAY INVISIBLE (1875 3175);
FORCEPROP 1 LAST BODY_TYPE PLUMBING
J 0
(1550 3350);
DISPLAY 0.872340 (1550 3350);
PAINT GREEN (1550 3350);
DISPLAY INVISIBLE (1550 3350);
FORCEPROP 2 LAST CDS_LIB mstr_standard
J 0
(1550 3300);
PAINT ORANGE (1550 3300);
DISPLAY INVISIBLE (1550 3300);
FORCEADD TAP..1
(1750 3350);
FORCEPROP 3 LASTPIN (1700 3350) SIG_NAME P3E_CPU0_PE3_OCP_RXN<4>
J 0
(1710 3360);
DISPLAY 0.659574 (1710 3360);
PAINT MONO (1710 3360);
DISPLAY INVISIBLE (1710 3360);
FORCEPROP 1 LASTPIN (1700 3350) BN 4
J 0
(1688 3358);
DISPLAY 0.617021 (1688 3358);
PAINT GREEN (1688 3358);
FORCEPROP 1 LAST PATH I112
J 0
(1748 3350);
DISPLAY 0.872340 (1748 3350);
PAINT GREEN (1748 3350);
DISPLAY INVISIBLE (1748 3350);
FORCEPROP 1 LAST HDL_TAP TRUE
J 0
(2075 3225);
DISPLAY 0.872340 (2075 3225);
PAINT ORANGE (2075 3225);
DISPLAY INVISIBLE (2075 3225);
FORCEPROP 1 LAST BODY_TYPE PLUMBING
J 0
(1750 3400);
DISPLAY 0.872340 (1750 3400);
PAINT GREEN (1750 3400);
DISPLAY INVISIBLE (1750 3400);
FORCEPROP 2 LAST CDS_LIB mstr_standard
J 0
(1750 3350);
PAINT ORANGE (1750 3350);
DISPLAY INVISIBLE (1750 3350);
FORCEADD TAP..1
(1750 3550);
FORCEPROP 3 LASTPIN (1700 3550) SIG_NAME P3E_CPU0_PE3_OCP_RXN<5>
J 0
(1710 3560);
DISPLAY 0.659574 (1710 3560);
PAINT MONO (1710 3560);
DISPLAY INVISIBLE (1710 3560);
FORCEPROP 1 LASTPIN (1700 3550) BN 5
J 0
(1688 3558);
DISPLAY 0.617021 (1688 3558);
PAINT GREEN (1688 3558);
FORCEPROP 1 LAST PATH I113
J 0
(1748 3550);
DISPLAY 0.872340 (1748 3550);
PAINT GREEN (1748 3550);
DISPLAY INVISIBLE (1748 3550);
FORCEPROP 1 LAST HDL_TAP TRUE
J 0
(2075 3425);
DISPLAY 0.872340 (2075 3425);
PAINT ORANGE (2075 3425);
DISPLAY INVISIBLE (2075 3425);
FORCEPROP 1 LAST BODY_TYPE PLUMBING
J 0
(1750 3600);
DISPLAY 0.872340 (1750 3600);
PAINT GREEN (1750 3600);
DISPLAY INVISIBLE (1750 3600);
FORCEPROP 2 LAST CDS_LIB mstr_standard
J 0
(1750 3550);
PAINT ORANGE (1750 3550);
DISPLAY INVISIBLE (1750 3550);
FORCEADD TAP..1
(1550 3500);
FORCEPROP 3 LASTPIN (1500 3500) SIG_NAME P3E_CPU0_PE3_OCP_RXP<5>
J 0
(1510 3510);
DISPLAY 0.659574 (1510 3510);
PAINT MONO (1510 3510);
DISPLAY INVISIBLE (1510 3510);
FORCEPROP 1 LASTPIN (1500 3500) BN 5
J 0
(1488 3508);
DISPLAY 0.617021 (1488 3508);
PAINT GREEN (1488 3508);
FORCEPROP 1 LAST PATH I114
J 0
(1548 3500);
DISPLAY 0.872340 (1548 3500);
PAINT GREEN (1548 3500);
DISPLAY INVISIBLE (1548 3500);
FORCEPROP 1 LAST HDL_TAP TRUE
J 0
(1875 3375);
DISPLAY 0.872340 (1875 3375);
PAINT ORANGE (1875 3375);
DISPLAY INVISIBLE (1875 3375);
FORCEPROP 1 LAST BODY_TYPE PLUMBING
J 0
(1550 3550);
DISPLAY 0.872340 (1550 3550);
PAINT GREEN (1550 3550);
DISPLAY INVISIBLE (1550 3550);
FORCEPROP 2 LAST CDS_LIB mstr_standard
J 0
(1550 3500);
PAINT ORANGE (1550 3500);
DISPLAY INVISIBLE (1550 3500);
FORCEADD TAP..1
(1550 3700);
FORCEPROP 3 LASTPIN (1500 3700) SIG_NAME P3E_CPU0_PE3_OCP_RXP<6>
J 0
(1510 3710);
DISPLAY 0.659574 (1510 3710);
PAINT MONO (1510 3710);
DISPLAY INVISIBLE (1510 3710);
FORCEPROP 1 LASTPIN (1500 3700) BN 6
J 0
(1488 3708);
DISPLAY 0.617021 (1488 3708);
PAINT GREEN (1488 3708);
FORCEPROP 1 LAST PATH I115
J 0
(1548 3700);
DISPLAY 0.872340 (1548 3700);
PAINT GREEN (1548 3700);
DISPLAY INVISIBLE (1548 3700);
FORCEPROP 1 LAST HDL_TAP TRUE
J 0
(1875 3575);
DISPLAY 0.872340 (1875 3575);
PAINT ORANGE (1875 3575);
DISPLAY INVISIBLE (1875 3575);
FORCEPROP 1 LAST BODY_TYPE PLUMBING
J 0
(1550 3750);
DISPLAY 0.872340 (1550 3750);
PAINT GREEN (1550 3750);
DISPLAY INVISIBLE (1550 3750);
FORCEPROP 2 LAST CDS_LIB mstr_standard
J 0
(1550 3700);
PAINT ORANGE (1550 3700);
DISPLAY INVISIBLE (1550 3700);
FORCEADD TAP..1
(1750 3750);
FORCEPROP 3 LASTPIN (1700 3750) SIG_NAME P3E_CPU0_PE3_OCP_RXN<6>
J 0
(1710 3760);
DISPLAY 0.659574 (1710 3760);
PAINT MONO (1710 3760);
DISPLAY INVISIBLE (1710 3760);
FORCEPROP 1 LASTPIN (1700 3750) BN 6
J 0
(1688 3758);
DISPLAY 0.617021 (1688 3758);
PAINT GREEN (1688 3758);
FORCEPROP 1 LAST PATH I116
J 0
(1748 3750);
DISPLAY 0.872340 (1748 3750);
PAINT GREEN (1748 3750);
DISPLAY INVISIBLE (1748 3750);
FORCEPROP 1 LAST HDL_TAP TRUE
J 0
(2075 3625);
DISPLAY 0.872340 (2075 3625);
PAINT ORANGE (2075 3625);
DISPLAY INVISIBLE (2075 3625);
FORCEPROP 1 LAST BODY_TYPE PLUMBING
J 0
(1750 3800);
DISPLAY 0.872340 (1750 3800);
PAINT GREEN (1750 3800);
DISPLAY INVISIBLE (1750 3800);
FORCEPROP 2 LAST CDS_LIB mstr_standard
J 0
(1750 3750);
PAINT ORANGE (1750 3750);
DISPLAY INVISIBLE (1750 3750);
FORCEADD SCONN80_E67482007..1
R 2
(-50 3100);
FORCEPROP 2 LASTPIN (250 3250) $PN 33
J 0
(260 3260);
DISPLAY 0.617021 (260 3260);
PAINT ORANGE (260 3260);
FORCEPROP 2 LASTPIN (250 4050) $PN 1
J 0
(260 4060);
DISPLAY 0.617021 (260 4060);
PAINT ORANGE (260 4060);
FORCEPROP 2 LASTPIN (-350 4050) $PN 2
J 2
(-360 4060);
DISPLAY 0.617021 (-360 4060);
PAINT ORANGE (-360 4060);
FORCEPROP 2 LASTPIN (250 4000) $PN 3
J 0
(260 4010);
DISPLAY 0.617021 (260 4010);
PAINT ORANGE (260 4010);
FORCEPROP 2 LASTPIN (-350 4000) $PN 4
J 2
(-360 4010);
DISPLAY 0.617021 (-360 4010);
PAINT ORANGE (-360 4010);
FORCEPROP 2 LASTPIN (250 3950) $PN 5
J 0
(260 3960);
DISPLAY 0.617021 (260 3960);
PAINT ORANGE (260 3960);
FORCEPROP 2 LASTPIN (-350 3950) $PN 6
J 2
(-360 3960);
DISPLAY 0.617021 (-360 3960);
PAINT ORANGE (-360 3960);
FORCEPROP 2 LASTPIN (250 3900) $PN 7
J 0
(260 3910);
DISPLAY 0.617021 (260 3910);
PAINT ORANGE (260 3910);
FORCEPROP 2 LASTPIN (-350 3900) $PN 8
J 2
(-360 3910);
DISPLAY 0.617021 (-360 3910);
PAINT ORANGE (-360 3910);
FORCEPROP 2 LASTPIN (250 3850) $PN 9
J 0
(260 3860);
DISPLAY 0.617021 (260 3860);
PAINT ORANGE (260 3860);
FORCEPROP 2 LASTPIN (-350 3850) $PN 10
J 2
(-360 3860);
DISPLAY 0.617021 (-360 3860);
PAINT ORANGE (-360 3860);
FORCEPROP 2 LASTPIN (250 3800) $PN 11
J 0
(260 3810);
DISPLAY 0.617021 (260 3810);
PAINT ORANGE (260 3810);
FORCEPROP 2 LASTPIN (-350 3800) $PN 12
J 2
(-360 3810);
DISPLAY 0.617021 (-360 3810);
PAINT ORANGE (-360 3810);
FORCEPROP 2 LASTPIN (250 3750) $PN 13
J 0
(260 3760);
DISPLAY 0.617021 (260 3760);
PAINT ORANGE (260 3760);
FORCEPROP 2 LASTPIN (-350 3750) $PN 14
J 2
(-360 3760);
DISPLAY 0.617021 (-360 3760);
PAINT ORANGE (-360 3760);
FORCEPROP 2 LASTPIN (250 3700) $PN 15
J 0
(260 3710);
DISPLAY 0.617021 (260 3710);
PAINT ORANGE (260 3710);
FORCEPROP 2 LASTPIN (-350 3700) $PN 16
J 2
(-360 3710);
DISPLAY 0.617021 (-360 3710);
PAINT ORANGE (-360 3710);
FORCEPROP 2 LASTPIN (250 3650) $PN 17
J 0
(260 3660);
DISPLAY 0.617021 (260 3660);
PAINT ORANGE (260 3660);
FORCEPROP 2 LASTPIN (-350 3650) $PN 18
J 2
(-360 3660);
DISPLAY 0.617021 (-360 3660);
PAINT ORANGE (-360 3660);
FORCEPROP 2 LASTPIN (250 3600) $PN 19
J 0
(260 3610);
DISPLAY 0.617021 (260 3610);
PAINT ORANGE (260 3610);
FORCEPROP 2 LASTPIN (-350 3600) $PN 20
J 2
(-360 3610);
DISPLAY 0.617021 (-360 3610);
PAINT ORANGE (-360 3610);
FORCEPROP 2 LASTPIN (250 3550) $PN 21
J 0
(260 3560);
DISPLAY 0.617021 (260 3560);
PAINT ORANGE (260 3560);
FORCEPROP 2 LASTPIN (-350 3550) $PN 22
J 2
(-360 3560);
DISPLAY 0.617021 (-360 3560);
PAINT ORANGE (-360 3560);
FORCEPROP 2 LASTPIN (250 3500) $PN 23
J 0
(260 3510);
DISPLAY 0.617021 (260 3510);
PAINT ORANGE (260 3510);
FORCEPROP 2 LASTPIN (-350 3500) $PN 24
J 2
(-360 3510);
DISPLAY 0.617021 (-360 3510);
PAINT ORANGE (-360 3510);
FORCEPROP 2 LASTPIN (250 3450) $PN 25
J 0
(260 3460);
DISPLAY 0.617021 (260 3460);
PAINT ORANGE (260 3460);
FORCEPROP 2 LASTPIN (-350 3450) $PN 26
J 2
(-360 3460);
DISPLAY 0.617021 (-360 3460);
PAINT ORANGE (-360 3460);
FORCEPROP 2 LASTPIN (250 3400) $PN 27
J 0
(260 3410);
DISPLAY 0.617021 (260 3410);
PAINT ORANGE (260 3410);
FORCEPROP 2 LASTPIN (250 3350) $PN 29
J 0
(260 3360);
DISPLAY 0.617021 (260 3360);
PAINT ORANGE (260 3360);
FORCEPROP 2 LASTPIN (-350 3350) $PN 30
J 2
(-360 3360);
DISPLAY 0.617021 (-360 3360);
PAINT ORANGE (-360 3360);
FORCEPROP 2 LASTPIN (250 3300) $PN 31
J 0
(260 3310);
DISPLAY 0.617021 (260 3310);
PAINT ORANGE (260 3310);
FORCEPROP 2 LASTPIN (-350 3250) $PN 34
J 2
(-360 3260);
DISPLAY 0.617021 (-360 3260);
PAINT ORANGE (-360 3260);
FORCEPROP 2 LASTPIN (250 3200) $PN 35
J 0
(260 3210);
DISPLAY 0.617021 (260 3210);
PAINT ORANGE (260 3210);
FORCEPROP 2 LASTPIN (-350 3200) $PN 36
J 2
(-360 3210);
DISPLAY 0.617021 (-360 3210);
PAINT ORANGE (-360 3210);
FORCEPROP 2 LASTPIN (250 3150) $PN 37
J 0
(260 3160);
DISPLAY 0.617021 (260 3160);
PAINT ORANGE (260 3160);
FORCEPROP 2 LASTPIN (-350 3150) $PN 38
J 2
(-360 3160);
DISPLAY 0.617021 (-360 3160);
PAINT ORANGE (-360 3160);
FORCEPROP 2 LASTPIN (250 3100) $PN 39
J 0
(260 3110);
DISPLAY 0.617021 (260 3110);
PAINT ORANGE (260 3110);
FORCEPROP 2 LASTPIN (-350 3100) $PN 40
J 2
(-360 3110);
DISPLAY 0.617021 (-360 3110);
PAINT ORANGE (-360 3110);
FORCEPROP 2 LASTPIN (-350 3050) $PN 42
J 2
(-360 3060);
DISPLAY 0.617021 (-360 3060);
PAINT ORANGE (-360 3060);
FORCEPROP 2 LASTPIN (250 3000) $PN 43
J 0
(260 3010);
DISPLAY 0.617021 (260 3010);
PAINT ORANGE (260 3010);
FORCEPROP 2 LASTPIN (-350 3000) $PN 44
J 2
(-360 3010);
DISPLAY 0.617021 (-360 3010);
PAINT ORANGE (-360 3010);
FORCEPROP 2 LASTPIN (-350 2950) $PN 46
J 2
(-360 2960);
DISPLAY 0.617021 (-360 2960);
PAINT ORANGE (-360 2960);
FORCEPROP 2 LASTPIN (250 2900) $PN 47
J 0
(260 2910);
DISPLAY 0.617021 (260 2910);
PAINT ORANGE (260 2910);
FORCEPROP 2 LASTPIN (-350 2900) $PN 48
J 2
(-360 2910);
DISPLAY 0.617021 (-360 2910);
PAINT ORANGE (-360 2910);
FORCEPROP 2 LASTPIN (250 2850) $PN 49
J 0
(260 2860);
DISPLAY 0.617021 (260 2860);
PAINT ORANGE (260 2860);
FORCEPROP 2 LASTPIN (-350 2850) $PN 50
J 2
(-360 2860);
DISPLAY 0.617021 (-360 2860);
PAINT ORANGE (-360 2860);
FORCEPROP 2 LASTPIN (250 2800) $PN 51
J 0
(260 2810);
DISPLAY 0.617021 (260 2810);
PAINT ORANGE (260 2810);
FORCEPROP 2 LASTPIN (-350 2800) $PN 52
J 2
(-360 2810);
DISPLAY 0.617021 (-360 2810);
PAINT ORANGE (-360 2810);
FORCEPROP 2 LASTPIN (250 2750) $PN 53
J 0
(260 2760);
DISPLAY 0.617021 (260 2760);
PAINT ORANGE (260 2760);
FORCEPROP 2 LASTPIN (-350 2750) $PN 54
J 2
(-360 2760);
DISPLAY 0.617021 (-360 2760);
PAINT ORANGE (-360 2760);
FORCEPROP 2 LASTPIN (250 2700) $PN 55
J 0
(260 2710);
DISPLAY 0.617021 (260 2710);
PAINT ORANGE (260 2710);
FORCEPROP 2 LASTPIN (250 2600) $PN 59
J 0
(260 2610);
DISPLAY 0.617021 (260 2610);
PAINT ORANGE (260 2610);
FORCEPROP 2 LASTPIN (-350 2600) $PN 60
J 2
(-360 2610);
DISPLAY 0.617021 (-360 2610);
PAINT ORANGE (-360 2610);
FORCEPROP 2 LASTPIN (-350 2550) $PN 62
J 2
(-360 2560);
DISPLAY 0.617021 (-360 2560);
PAINT ORANGE (-360 2560);
FORCEPROP 2 LASTPIN (250 2500) $PN 63
J 0
(260 2510);
DISPLAY 0.617021 (260 2510);
PAINT ORANGE (260 2510);
FORCEPROP 2 LASTPIN (-350 2500) $PN 64
J 2
(-360 2510);
DISPLAY 0.617021 (-360 2510);
PAINT ORANGE (-360 2510);
FORCEPROP 2 LASTPIN (250 2450) $PN 65
J 0
(260 2460);
DISPLAY 0.617021 (260 2460);
PAINT ORANGE (260 2460);
FORCEPROP 2 LASTPIN (-350 2450) $PN 66
J 2
(-360 2460);
DISPLAY 0.617021 (-360 2460);
PAINT ORANGE (-360 2460);
FORCEPROP 2 LASTPIN (250 2400) $PN 67
J 0
(260 2410);
DISPLAY 0.617021 (260 2410);
PAINT ORANGE (260 2410);
FORCEPROP 2 LASTPIN (-350 2400) $PN 68
J 2
(-360 2410);
DISPLAY 0.617021 (-360 2410);
PAINT ORANGE (-360 2410);
FORCEPROP 2 LASTPIN (250 2350) $PN 69
J 0
(260 2360);
DISPLAY 0.617021 (260 2360);
PAINT ORANGE (260 2360);
FORCEPROP 2 LASTPIN (-350 2350) $PN 70
J 2
(-360 2360);
DISPLAY 0.617021 (-360 2360);
PAINT ORANGE (-360 2360);
FORCEPROP 2 LASTPIN (250 2300) $PN 71
J 0
(260 2310);
DISPLAY 0.617021 (260 2310);
PAINT ORANGE (260 2310);
FORCEPROP 2 LASTPIN (-350 2300) $PN 72
J 2
(-360 2310);
DISPLAY 0.617021 (-360 2310);
PAINT ORANGE (-360 2310);
FORCEPROP 2 LASTPIN (250 2250) $PN 73
J 0
(260 2260);
DISPLAY 0.617021 (260 2260);
PAINT ORANGE (260 2260);
FORCEPROP 2 LASTPIN (-350 2250) $PN 74
J 2
(-360 2260);
DISPLAY 0.617021 (-360 2260);
PAINT ORANGE (-360 2260);
FORCEPROP 2 LASTPIN (250 2200) $PN 75
J 0
(260 2210);
DISPLAY 0.617021 (260 2210);
PAINT ORANGE (260 2210);
FORCEPROP 2 LASTPIN (-350 2200) $PN 76
J 2
(-360 2210);
DISPLAY 0.617021 (-360 2210);
PAINT ORANGE (-360 2210);
FORCEPROP 2 LASTPIN (250 2150) $PN 77
J 0
(260 2160);
DISPLAY 0.617021 (260 2160);
PAINT ORANGE (260 2160);
FORCEPROP 2 LASTPIN (-350 2150) $PN 78
J 2
(-360 2160);
DISPLAY 0.617021 (-360 2160);
PAINT ORANGE (-360 2160);
FORCEPROP 2 LASTPIN (250 2100) $PN 79
J 0
(260 2110);
DISPLAY 0.617021 (260 2110);
PAINT ORANGE (260 2110);
FORCEPROP 1 LAST MATERIAL CONN
J 2
(200 4275);
DISPLAY 0.617021 (200 4275);
PAINT SKYBLUE (200 4275);
FORCEPROP 1 LAST LOCATION J8E3
J 2
(150 4375);
DISPLAY 0.617021 (150 4375);
PAINT AQUA (150 4375);
FORCEPROP 2 LASTPIN (-350 3400) $PN 28
J 2
(-360 3410);
DISPLAY 0.617021 (-360 3410);
PAINT ORANGE (-360 3410);
FORCEPROP 2 LASTPIN (250 3050) $PN 41
J 0
(260 3060);
DISPLAY 0.617021 (260 3060);
PAINT ORANGE (260 3060);
FORCEPROP 2 LASTPIN (-350 3300) $PN 32
J 2
(-360 3310);
DISPLAY 0.617021 (-360 3310);
PAINT ORANGE (-360 3310);
FORCEPROP 2 LASTPIN (-350 2100) $PN 80
J 2
(-360 2110);
DISPLAY 0.617021 (-360 2110);
PAINT ORANGE (-360 2110);
FORCEPROP 2 LASTPIN (250 2650) $PN 57
J 0
(260 2660);
DISPLAY 0.617021 (260 2660);
PAINT ORANGE (260 2660);
FORCEPROP 2 LASTPIN (250 2950) $PN 45
J 0
(260 2960);
DISPLAY 0.617021 (260 2960);
PAINT ORANGE (260 2960);
FORCEPROP 2 LASTPIN (-350 2650) $PN 58
J 2
(-360 2660);
DISPLAY 0.617021 (-360 2660);
PAINT ORANGE (-360 2660);
FORCEPROP 2 LASTPIN (-350 2700) $PN 56
J 2
(-360 2710);
DISPLAY 0.617021 (-360 2710);
PAINT ORANGE (-360 2710);
FORCEPROP 1 LAST PART_NUMBER E67482-007
J 2
(200 1950);
DISPLAY 0.617021 (200 1950);
PAINT BLUE (200 1950);
FORCEPROP 2 LASTPIN (250 2550) $PN 61
J 0
(260 2560);
DISPLAY 0.617021 (260 2560);
PAINT ORANGE (260 2560);
FORCEPROP 0 LAST GROUP NO_KR
J 0
(-312 1913);
DISPLAY 0.638298 (-312 1913);
PAINT BROWN (-312 1913);
DISPLAY BOTH (-312 1913);
FORCEPROP 0 LAST ROOM IO_SLOT
J 2
(200 4400);
DISPLAY 1.021277 (200 4400);
PAINT ORANGE (200 4400);
DISPLAY INVISIBLE (200 4400);
FORCEPROP 1 LAST PATH I119
J 2
(-50 4276);
PAINT GREEN (-50 4276);
DISPLAY INVISIBLE (-50 4276);
FORCEPROP 2 LAST CDS_LOCATION J8E3
J 2
(150 4375);
DISPLAY 0.617021 (150 4375);
PAINT AQUA (150 4375);
DISPLAY INVISIBLE (150 4375);
FORCEPROP 2 LAST SEC 1
J 0
(200 4350);
DISPLAY 0.680851 (200 4350);
PAINT MONO (200 4350);
DISPLAY INVISIBLE (200 4350);
FORCEPROP 2 LAST SEC_TYPE SM
J 0
(200 4350);
DISPLAY 1.021277 (200 4350);
PAINT ORANGE (200 4350);
DISPLAY INVISIBLE (200 4350);
FORCEPROP 2 LAST CDS_LIB mstr_sconn
J 0
(-50 3100);
PAINT ORANGE (-50 3100);
DISPLAY INVISIBLE (-50 3100);
FORCEPROP 1 LAST CDS_LMAN_SYM_OUTLINE -250,1100,250,-1100
J 2
(-50 3100);
DISPLAY 0.468085 (-50 3100);
PAINT GREEN (-50 3100);
DISPLAY INVISIBLE (-50 3100);
FORCEPROP 1 LAST PACK_TYPE SM
J 2
(200 4375);
PAINT SKYBLUE (200 4375);
DISPLAY INVISIBLE (200 4375);
FORCEADD TAP..1
(1750 2700);
FORCEPROP 3 LASTPIN (1700 2700) SIG_NAME P3E_CPU0_PE3_OCP_RXN<1>
J 0
(1710 2710);
DISPLAY 0.659574 (1710 2710);
PAINT MONO (1710 2710);
DISPLAY INVISIBLE (1710 2710);
FORCEPROP 1 LASTPIN (1700 2700) BN 1
J 0
(1688 2708);
DISPLAY 0.617021 (1688 2708);
PAINT GREEN (1688 2708);
FORCEPROP 1 LAST PATH I140
J 0
(1748 2700);
DISPLAY 0.872340 (1748 2700);
PAINT GREEN (1748 2700);
DISPLAY INVISIBLE (1748 2700);
FORCEPROP 1 LAST HDL_TAP TRUE
J 0
(2075 2575);
DISPLAY 0.872340 (2075 2575);
PAINT ORANGE (2075 2575);
DISPLAY INVISIBLE (2075 2575);
FORCEPROP 1 LAST BODY_TYPE PLUMBING
J 0
(1750 2750);
DISPLAY 0.872340 (1750 2750);
PAINT GREEN (1750 2750);
DISPLAY INVISIBLE (1750 2750);
FORCEPROP 2 LAST CDS_LIB mstr_standard
J 0
(1750 2700);
PAINT ORANGE (1750 2700);
DISPLAY INVISIBLE (1750 2700);
FORCEADD TAP..1
(1750 2900);
FORCEPROP 3 LASTPIN (1700 2900) SIG_NAME P3E_CPU0_PE3_OCP_RXN<2>
J 0
(1710 2910);
DISPLAY 0.659574 (1710 2910);
PAINT MONO (1710 2910);
DISPLAY INVISIBLE (1710 2910);
FORCEPROP 1 LASTPIN (1700 2900) BN 2
J 0
(1688 2908);
DISPLAY 0.617021 (1688 2908);
PAINT GREEN (1688 2908);
FORCEPROP 1 LAST PATH I141
J 0
(1748 2900);
DISPLAY 0.872340 (1748 2900);
PAINT GREEN (1748 2900);
DISPLAY INVISIBLE (1748 2900);
FORCEPROP 1 LAST HDL_TAP TRUE
J 0
(2075 2775);
DISPLAY 0.872340 (2075 2775);
PAINT ORANGE (2075 2775);
DISPLAY INVISIBLE (2075 2775);
FORCEPROP 1 LAST BODY_TYPE PLUMBING
J 0
(1750 2950);
DISPLAY 0.872340 (1750 2950);
PAINT GREEN (1750 2950);
DISPLAY INVISIBLE (1750 2950);
FORCEPROP 2 LAST CDS_LIB mstr_standard
J 0
(1750 2900);
PAINT ORANGE (1750 2900);
DISPLAY INVISIBLE (1750 2900);
FORCEADD TAP..1
(1550 2950);
FORCEPROP 3 LASTPIN (1500 2950) SIG_NAME P3E_CPU0_PE3_OCP_RXP<2>
J 0
(1510 2960);
DISPLAY 0.659574 (1510 2960);
PAINT MONO (1510 2960);
DISPLAY INVISIBLE (1510 2960);
FORCEPROP 1 LASTPIN (1500 2950) BN 2
J 0
(1488 2958);
DISPLAY 0.617021 (1488 2958);
PAINT GREEN (1488 2958);
FORCEPROP 1 LAST PATH I142
J 0
(1548 2950);
DISPLAY 0.872340 (1548 2950);
PAINT GREEN (1548 2950);
DISPLAY INVISIBLE (1548 2950);
FORCEPROP 1 LAST HDL_TAP TRUE
J 0
(1875 2825);
DISPLAY 0.872340 (1875 2825);
PAINT ORANGE (1875 2825);
DISPLAY INVISIBLE (1875 2825);
FORCEPROP 1 LAST BODY_TYPE PLUMBING
J 0
(1550 3000);
DISPLAY 0.872340 (1550 3000);
PAINT GREEN (1550 3000);
DISPLAY INVISIBLE (1550 3000);
FORCEPROP 2 LAST CDS_LIB mstr_standard
J 0
(1550 2950);
PAINT ORANGE (1550 2950);
DISPLAY INVISIBLE (1550 2950);
FORCEADD OFFPAGE..1
R 2
(3000 2200);
FORCEPROP 2 LAST $XR0 190 
J 0
(3186 2200);
DISPLAY 0.638298 (3186 2200);
PAINT MONO (3186 2200);
FORCEPROP 2 LAST PATH I143
J 0
(3200 2250);
DISPLAY 1.021277 (3200 2250);
PAINT ORANGE (3200 2250);
DISPLAY INVISIBLE (3200 2250);
FORCEPROP 1 LAST COMMENT_BODY TRUE
J 2
(2875 2100);
DISPLAY 0.872340 (2875 2100);
PAINT GREEN (2875 2100);
DISPLAY INVISIBLE (2875 2100);
FORCEPROP 1 LAST OFFPAGE TRUE
J 2
(2675 2075);
DISPLAY 0.872340 (2675 2075);
PAINT GREEN (2675 2075);
DISPLAY INVISIBLE (2675 2075);
FORCEPROP 2 LAST CDS_LIB mstr_standard
J 0
(3000 2200);
PAINT ORANGE (3000 2200);
DISPLAY INVISIBLE (3000 2200);
FORCEADD OFFPAGE..1
R 2
(3000 2150);
FORCEPROP 2 LAST $XR0 190 
J 0
(3186 2150);
DISPLAY 0.638298 (3186 2150);
PAINT MONO (3186 2150);
FORCEPROP 2 LAST PATH I144
J 0
(3200 2200);
DISPLAY 1.021277 (3200 2200);
PAINT ORANGE (3200 2200);
DISPLAY INVISIBLE (3200 2200);
FORCEPROP 1 LAST COMMENT_BODY TRUE
J 2
(2875 2050);
DISPLAY 0.872340 (2875 2050);
PAINT GREEN (2875 2050);
DISPLAY INVISIBLE (2875 2050);
FORCEPROP 1 LAST OFFPAGE TRUE
J 2
(2675 2025);
DISPLAY 0.872340 (2675 2025);
PAINT GREEN (2675 2025);
DISPLAY INVISIBLE (2675 2025);
FORCEPROP 2 LAST CDS_LIB mstr_standard
J 0
(3000 2150);
PAINT ORANGE (3000 2150);
DISPLAY INVISIBLE (3000 2150);
FORCEADD RES..1
(2275 2200);
FORCEPROP 1 LASTPIN (2175 2200) $PN 1
J 0
(2187 2212);
DISPLAY 0.617021 (2187 2212);
PAINT ORANGE (2187 2212);
FORCEPROP 1 LASTPIN (2375 2200) $PN 2
J 0
(2337 2212);
DISPLAY 0.617021 (2337 2212);
PAINT ORANGE (2337 2212);
FORCEPROP 1 LAST WATTAGE 1/16W
J 2
(2250 2050);
DISPLAY 0.617021 (2250 2050);
PAINT SKYBLUE (2250 2050);
FORCEPROP 1 LAST MATERIAL CHIP
J 0
(2275 2050);
DISPLAY 0.617021 (2275 2050);
PAINT SKYBLUE (2275 2050);
FORCEPROP 1 LAST PACK_TYPE 0402
J 0
(2375 2125);
DISPLAY 0.617021 (2375 2125);
PAINT SKYBLUE (2375 2125);
FORCEPROP 1 LAST TOLERANCE 1%
J 0
(2275 2100);
DISPLAY 0.617021 (2275 2100);
PAINT SKYBLUE (2275 2100);
FORCEPROP 1 LAST VALUE 200.0
J 2
(2250 2100);
DISPLAY 0.617021 (2250 2100);
PAINT SKYBLUE (2250 2100);
FORCEPROP 1 LAST PART_NUMBER G21796-004
J 0
(2100 2150);
DISPLAY 0.617021 (2100 2150);
PAINT BLUE (2100 2150);
FORCEPROP 1 LAST LOCATION R9E10
J 0
(2225 2250);
DISPLAY 0.617021 (2225 2250);
PAINT AQUA (2225 2250);
FORCEPROP 0 LAST ROOM IO_SLOT
J 0
(2225 2400);
DISPLAY 1.021277 (2225 2400);
PAINT ORANGE (2225 2400);
DISPLAY INVISIBLE (2225 2400);
FORCEPROP 1 LAST PATH I145
J 0
(2225 2350);
DISPLAY 0.978723 (2225 2350);
PAINT WHITE (2225 2350);
DISPLAY INVISIBLE (2225 2350);
FORCEPROP 2 LAST CDS_LOCATION R9E10
J 0
(2225 2250);
DISPLAY 0.617021 (2225 2250);
PAINT AQUA (2225 2250);
DISPLAY INVISIBLE (2225 2250);
FORCEPROP 2 LAST SEC 1
J 0
(2225 2400);
DISPLAY 0.680851 (2225 2400);
PAINT MONO (2225 2400);
DISPLAY INVISIBLE (2225 2400);
FORCEPROP 2 LAST SEC_TYPE 0402
J 0
(2225 2400);
DISPLAY 1.021277 (2225 2400);
PAINT ORANGE (2225 2400);
DISPLAY INVISIBLE (2225 2400);
FORCEPROP 2 LAST CDS_LIB mstr_discrete
J 0
(2275 2200);
PAINT ORANGE (2275 2200);
DISPLAY INVISIBLE (2275 2200);
FORCEADD OFFPAGE..1
R 2
(3000 2100);
FORCEPROP 2 LAST $XR0 190 
J 0
(3186 2100);
DISPLAY 0.638298 (3186 2100);
PAINT MONO (3186 2100);
FORCEPROP 2 LAST PATH I146
J 0
(3200 2150);
DISPLAY 1.021277 (3200 2150);
PAINT ORANGE (3200 2150);
DISPLAY INVISIBLE (3200 2150);
FORCEPROP 1 LAST COMMENT_BODY TRUE
J 2
(2875 2000);
DISPLAY 0.872340 (2875 2000);
PAINT GREEN (2875 2000);
DISPLAY INVISIBLE (2875 2000);
FORCEPROP 1 LAST OFFPAGE TRUE
J 2
(2675 1975);
DISPLAY 0.872340 (2675 1975);
PAINT GREEN (2675 1975);
DISPLAY INVISIBLE (2675 1975);
FORCEPROP 2 LAST CDS_LIB mstr_standard
J 0
(3000 2100);
PAINT ORANGE (3000 2100);
DISPLAY INVISIBLE (3000 2100);
FORCEADD TAP..1
(1550 2750);
FORCEPROP 3 LASTPIN (1500 2750) SIG_NAME P3E_CPU0_PE3_OCP_RXP<1>
J 0
(1510 2760);
DISPLAY 0.659574 (1510 2760);
PAINT MONO (1510 2760);
DISPLAY INVISIBLE (1510 2760);
FORCEPROP 1 LASTPIN (1500 2750) BN 1
J 0
(1488 2758);
DISPLAY 0.617021 (1488 2758);
PAINT GREEN (1488 2758);
FORCEPROP 1 LAST PATH I147
J 0
(1548 2750);
DISPLAY 0.872340 (1548 2750);
PAINT GREEN (1548 2750);
DISPLAY INVISIBLE (1548 2750);
FORCEPROP 1 LAST HDL_TAP TRUE
J 0
(1875 2625);
DISPLAY 0.872340 (1875 2625);
PAINT ORANGE (1875 2625);
DISPLAY INVISIBLE (1875 2625);
FORCEPROP 1 LAST BODY_TYPE PLUMBING
J 0
(1550 2800);
DISPLAY 0.872340 (1550 2800);
PAINT GREEN (1550 2800);
DISPLAY INVISIBLE (1550 2800);
FORCEPROP 2 LAST CDS_LIB mstr_standard
J 0
(1550 2750);
PAINT ORANGE (1550 2750);
DISPLAY INVISIBLE (1550 2750);
FORCEADD TAP..1
(1750 2500);
FORCEPROP 3 LASTPIN (1700 2500) SIG_NAME P3E_CPU0_PE3_OCP_RXN<0>
J 0
(1710 2510);
DISPLAY 0.659574 (1710 2510);
PAINT MONO (1710 2510);
DISPLAY INVISIBLE (1710 2510);
FORCEPROP 1 LASTPIN (1700 2500) BN 0
J 0
(1688 2508);
DISPLAY 0.617021 (1688 2508);
PAINT GREEN (1688 2508);
FORCEPROP 1 LAST PATH I148
J 0
(1748 2500);
DISPLAY 0.872340 (1748 2500);
PAINT GREEN (1748 2500);
DISPLAY INVISIBLE (1748 2500);
FORCEPROP 1 LAST HDL_TAP TRUE
J 0
(2075 2375);
DISPLAY 0.872340 (2075 2375);
PAINT ORANGE (2075 2375);
DISPLAY INVISIBLE (2075 2375);
FORCEPROP 1 LAST BODY_TYPE PLUMBING
J 0
(1750 2550);
DISPLAY 0.872340 (1750 2550);
PAINT GREEN (1750 2550);
DISPLAY INVISIBLE (1750 2550);
FORCEPROP 2 LAST CDS_LIB mstr_standard
J 0
(1750 2500);
PAINT ORANGE (1750 2500);
DISPLAY INVISIBLE (1750 2500);
FORCEADD TAP..1
(1550 2550);
FORCEPROP 3 LASTPIN (1500 2550) SIG_NAME P3E_CPU0_PE3_OCP_RXP<0>
J 0
(1510 2560);
DISPLAY 0.659574 (1510 2560);
PAINT MONO (1510 2560);
DISPLAY INVISIBLE (1510 2560);
FORCEPROP 1 LASTPIN (1500 2550) BN 0
J 0
(1488 2558);
DISPLAY 0.617021 (1488 2558);
PAINT GREEN (1488 2558);
FORCEPROP 1 LAST PATH I149
J 0
(1548 2550);
DISPLAY 0.872340 (1548 2550);
PAINT GREEN (1548 2550);
DISPLAY INVISIBLE (1548 2550);
FORCEPROP 1 LAST HDL_TAP TRUE
J 0
(1875 2425);
DISPLAY 0.872340 (1875 2425);
PAINT ORANGE (1875 2425);
DISPLAY INVISIBLE (1875 2425);
FORCEPROP 1 LAST BODY_TYPE PLUMBING
J 0
(1550 2600);
DISPLAY 0.872340 (1550 2600);
PAINT GREEN (1550 2600);
DISPLAY INVISIBLE (1550 2600);
FORCEPROP 2 LAST CDS_LIB mstr_standard
J 0
(1550 2550);
PAINT ORANGE (1550 2550);
DISPLAY INVISIBLE (1550 2550);
FORCEADD RES..1
(1725 2150);
FORCEPROP 1 LASTPIN (1625 2150) $PN 1
J 0
(1637 2162);
DISPLAY 0.617021 (1637 2162);
PAINT ORANGE (1637 2162);
FORCEPROP 1 LASTPIN (1825 2150) $PN 2
J 0
(1787 2162);
DISPLAY 0.617021 (1787 2162);
PAINT ORANGE (1787 2162);
FORCEPROP 1 LAST WATTAGE 1/16W
J 2
(1700 2000);
DISPLAY 0.617021 (1700 2000);
PAINT SKYBLUE (1700 2000);
FORCEPROP 1 LAST MATERIAL CHIP
J 0
(1725 2000);
DISPLAY 0.617021 (1725 2000);
PAINT SKYBLUE (1725 2000);
FORCEPROP 1 LAST PACK_TYPE 0402
J 0
(1825 2075);
DISPLAY 0.617021 (1825 2075);
PAINT SKYBLUE (1825 2075);
FORCEPROP 1 LAST TOLERANCE 1%
J 0
(1725 2050);
DISPLAY 0.617021 (1725 2050);
PAINT SKYBLUE (1725 2050);
FORCEPROP 1 LAST VALUE 200.0
J 2
(1700 2050);
DISPLAY 0.617021 (1700 2050);
PAINT SKYBLUE (1700 2050);
FORCEPROP 1 LAST PART_NUMBER G21796-004
J 0
(1550 2100);
DISPLAY 0.617021 (1550 2100);
PAINT BLUE (1550 2100);
FORCEPROP 1 LAST LOCATION R9E11
J 0
(1675 2200);
DISPLAY 0.617021 (1675 2200);
PAINT AQUA (1675 2200);
FORCEPROP 0 LAST ROOM IO_SLOT
J 0
(1675 2350);
DISPLAY 1.021277 (1675 2350);
PAINT ORANGE (1675 2350);
DISPLAY INVISIBLE (1675 2350);
FORCEPROP 1 LAST PATH I150
J 0
(1675 2300);
DISPLAY 0.978723 (1675 2300);
PAINT WHITE (1675 2300);
DISPLAY INVISIBLE (1675 2300);
FORCEPROP 2 LAST CDS_LOCATION R9E11
J 0
(1675 2200);
DISPLAY 0.617021 (1675 2200);
PAINT AQUA (1675 2200);
DISPLAY INVISIBLE (1675 2200);
FORCEPROP 2 LAST SEC 1
J 0
(1675 2350);
DISPLAY 0.680851 (1675 2350);
PAINT MONO (1675 2350);
DISPLAY INVISIBLE (1675 2350);
FORCEPROP 2 LAST SEC_TYPE 0402
J 0
(1675 2350);
DISPLAY 1.021277 (1675 2350);
PAINT ORANGE (1675 2350);
DISPLAY INVISIBLE (1675 2350);
FORCEPROP 2 LAST CDS_LIB mstr_discrete
J 0
(1725 2150);
PAINT ORANGE (1725 2150);
DISPLAY INVISIBLE (1725 2150);
FORCEADD OFFPAGE..1
R 2
(1600 2350);
FORCEPROP 2 LAST $XR0 114 
J 0
(1786 2350);
DISPLAY 0.638298 (1786 2350);
PAINT MONO (1786 2350);
FORCEPROP 2 LAST PATH I151
J 0
(1800 2400);
DISPLAY 1.021277 (1800 2400);
PAINT ORANGE (1800 2400);
DISPLAY INVISIBLE (1800 2400);
FORCEPROP 1 LAST COMMENT_BODY TRUE
J 2
(1475 2250);
DISPLAY 0.872340 (1475 2250);
PAINT GREEN (1475 2250);
DISPLAY INVISIBLE (1475 2250);
FORCEPROP 1 LAST OFFPAGE TRUE
J 2
(1275 2225);
DISPLAY 0.872340 (1275 2225);
PAINT GREEN (1275 2225);
DISPLAY INVISIBLE (1275 2225);
FORCEPROP 2 LAST CDS_LIB mstr_standard
J 2
(1600 2350);
PAINT ORANGE (1600 2350);
DISPLAY INVISIBLE (1600 2350);
FORCEADD OFFPAGE..1
R 2
(1600 2300);
FORCEPROP 2 LAST $XR0 114 
J 0
(1786 2300);
DISPLAY 0.638298 (1786 2300);
PAINT MONO (1786 2300);
FORCEPROP 2 LAST PATH I152
J 0
(1800 2350);
DISPLAY 1.021277 (1800 2350);
PAINT ORANGE (1800 2350);
DISPLAY INVISIBLE (1800 2350);
FORCEPROP 1 LAST COMMENT_BODY TRUE
J 2
(1475 2200);
DISPLAY 0.872340 (1475 2200);
PAINT GREEN (1475 2200);
DISPLAY INVISIBLE (1475 2200);
FORCEPROP 1 LAST OFFPAGE TRUE
J 2
(1275 2175);
DISPLAY 0.872340 (1275 2175);
PAINT GREEN (1275 2175);
DISPLAY INVISIBLE (1275 2175);
FORCEPROP 2 LAST CDS_LIB mstr_standard
J 0
(1600 2300);
PAINT ORANGE (1600 2300);
DISPLAY INVISIBLE (1600 2300);
FORCEADD RES..1
(1275 2100);
FORCEPROP 1 LAST MATERIAL CHIP
J 0
(1275 1950);
DISPLAY 0.617021 (1275 1950);
PAINT SKYBLUE (1275 1950);
FORCEPROP 1 LAST TOLERANCE 1%
J 0
(1275 2000);
DISPLAY 0.617021 (1275 2000);
PAINT SKYBLUE (1275 2000);
FORCEPROP 1 LAST PART_NUMBER G21796-004
J 0
(1100 2050);
DISPLAY 0.617021 (1100 2050);
PAINT BLUE (1100 2050);
FORCEPROP 1 LAST PACK_TYPE 0402
J 0
(1375 2025);
DISPLAY 0.617021 (1375 2025);
PAINT SKYBLUE (1375 2025);
FORCEPROP 1 LASTPIN (1175 2100) $PN 1
J 0
(1187 2112);
DISPLAY 0.617021 (1187 2112);
PAINT ORANGE (1187 2112);
FORCEPROP 1 LASTPIN (1375 2100) $PN 2
J 0
(1337 2112);
DISPLAY 0.617021 (1337 2112);
PAINT ORANGE (1337 2112);
FORCEPROP 1 LAST WATTAGE 1/16W
J 2
(1250 1950);
DISPLAY 0.617021 (1250 1950);
PAINT SKYBLUE (1250 1950);
FORCEPROP 1 LAST VALUE 200.0
J 2
(1250 2000);
DISPLAY 0.617021 (1250 2000);
PAINT SKYBLUE (1250 2000);
FORCEPROP 1 LAST LOCATION R9E12
J 0
(1225 2150);
DISPLAY 0.617021 (1225 2150);
PAINT AQUA (1225 2150);
FORCEPROP 0 LAST ROOM IO_SLOT
J 0
(1225 2300);
DISPLAY 1.021277 (1225 2300);
PAINT ORANGE (1225 2300);
DISPLAY INVISIBLE (1225 2300);
FORCEPROP 1 LAST PATH I153
J 0
(1225 2250);
DISPLAY 0.978723 (1225 2250);
PAINT WHITE (1225 2250);
DISPLAY INVISIBLE (1225 2250);
FORCEPROP 2 LAST CDS_LOCATION R9E12
J 0
(1225 2150);
DISPLAY 0.617021 (1225 2150);
PAINT AQUA (1225 2150);
DISPLAY INVISIBLE (1225 2150);
FORCEPROP 2 LAST SEC 1
J 0
(1225 2300);
DISPLAY 0.680851 (1225 2300);
PAINT MONO (1225 2300);
DISPLAY INVISIBLE (1225 2300);
FORCEPROP 2 LAST SEC_TYPE 0402
J 0
(1225 2300);
DISPLAY 1.021277 (1225 2300);
PAINT ORANGE (1225 2300);
DISPLAY INVISIBLE (1225 2300);
FORCEPROP 2 LAST CDS_LIB mstr_discrete
J 0
(1275 2100);
PAINT ORANGE (1275 2100);
DISPLAY INVISIBLE (1275 2100);
FORCEADD GND..1
(625 1900);
FORCEPROP 3 LASTPIN (625 1950) SIG_NAME GND\g
J 0
(635 1960);
DISPLAY 0.659574 (635 1960);
PAINT MONO (635 1960);
DISPLAY INVISIBLE (635 1960);
FORCEPROP 1 LAST HDL_POWER GND
J 0
(625 2050);
DISPLAY 0.872340 (625 2050);
PAINT GREEN (625 2050);
DISPLAY INVISIBLE (625 2050);
FORCEPROP 1 LAST PATH I154
J 0
(700 1900);
DISPLAY 0.872340 (700 1900);
PAINT AQUA (700 1900);
DISPLAY INVISIBLE (700 1900);
FORCEPROP 1 LAST BODY_TYPE PLUMBING
J 0
(580 1857);
DISPLAY 0.340426 (580 1857);
PAINT GREEN (580 1857);
DISPLAY INVISIBLE (580 1857);
FORCEPROP 1 LAST SIZE 1B
J 0
(700 1850);
DISPLAY 0.872340 (700 1850);
PAINT AQUA (700 1850);
DISPLAY INVISIBLE (700 1850);
FORCEPROP 2 LAST CDS_LIB mstr_symbols
J 0
(625 1900);
PAINT ORANGE (625 1900);
DISPLAY INVISIBLE (625 1900);
FORCEPROP 1 LAST VOLTAGE 0
J 0
(625 1900);
PAINT SKYBLUE (625 1900);
DISPLAY INVISIBLE (625 1900);
FORCEADD TAP..1
R 2
(-1675 3050);
FORCEPROP 3 LASTPIN (-1625 3050) SIG_NAME P3E_OCP_CPU0_PE3_C_TXP<3>
J 0
(-1615 3060);
DISPLAY 0.659574 (-1615 3060);
PAINT MONO (-1615 3060);
DISPLAY INVISIBLE (-1615 3060);
FORCEPROP 1 LASTPIN (-1625 3050) BN 3
J 2
(-1613 3058);
DISPLAY 0.617021 (-1613 3058);
PAINT GREEN (-1613 3058);
FORCEPROP 1 LAST PATH I155
J 2
(-1673 3050);
DISPLAY 0.872340 (-1673 3050);
PAINT GREEN (-1673 3050);
DISPLAY INVISIBLE (-1673 3050);
FORCEPROP 1 LAST HDL_TAP TRUE
J 2
(-2000 2925);
DISPLAY 0.872340 (-2000 2925);
PAINT ORANGE (-2000 2925);
DISPLAY INVISIBLE (-2000 2925);
FORCEPROP 1 LAST BODY_TYPE PLUMBING
J 2
(-1675 3100);
DISPLAY 0.872340 (-1675 3100);
PAINT GREEN (-1675 3100);
DISPLAY INVISIBLE (-1675 3100);
FORCEPROP 2 LAST CDS_LIB mstr_standard
J 0
(-1675 3050);
PAINT ORANGE (-1675 3050);
DISPLAY INVISIBLE (-1675 3050);
FORCEADD TAP..1
R 2
(-1675 2650);
FORCEPROP 3 LASTPIN (-1625 2650) SIG_NAME P3E_OCP_CPU0_PE3_C_TXP<1>
J 0
(-1615 2660);
DISPLAY 0.659574 (-1615 2660);
PAINT MONO (-1615 2660);
DISPLAY INVISIBLE (-1615 2660);
FORCEPROP 1 LASTPIN (-1625 2650) BN 1
J 2
(-1613 2658);
DISPLAY 0.617021 (-1613 2658);
PAINT GREEN (-1613 2658);
FORCEPROP 1 LAST PATH I156
J 2
(-1673 2650);
DISPLAY 0.872340 (-1673 2650);
PAINT GREEN (-1673 2650);
DISPLAY INVISIBLE (-1673 2650);
FORCEPROP 1 LAST HDL_TAP TRUE
J 2
(-2000 2525);
DISPLAY 0.872340 (-2000 2525);
PAINT ORANGE (-2000 2525);
DISPLAY INVISIBLE (-2000 2525);
FORCEPROP 1 LAST BODY_TYPE PLUMBING
J 2
(-1675 2700);
DISPLAY 0.872340 (-1675 2700);
PAINT GREEN (-1675 2700);
DISPLAY INVISIBLE (-1675 2700);
FORCEPROP 2 LAST CDS_LIB mstr_standard
J 0
(-1675 2650);
PAINT ORANGE (-1675 2650);
DISPLAY INVISIBLE (-1675 2650);
FORCEADD TAP..1
R 2
(-1675 2850);
FORCEPROP 3 LASTPIN (-1625 2850) SIG_NAME P3E_OCP_CPU0_PE3_C_TXP<2>
J 0
(-1615 2860);
DISPLAY 0.659574 (-1615 2860);
PAINT MONO (-1615 2860);
DISPLAY INVISIBLE (-1615 2860);
FORCEPROP 1 LASTPIN (-1625 2850) BN 2
J 2
(-1613 2858);
DISPLAY 0.617021 (-1613 2858);
PAINT GREEN (-1613 2858);
FORCEPROP 1 LAST PATH I157
J 2
(-1673 2850);
DISPLAY 0.872340 (-1673 2850);
PAINT GREEN (-1673 2850);
DISPLAY INVISIBLE (-1673 2850);
FORCEPROP 1 LAST HDL_TAP TRUE
J 2
(-2000 2725);
DISPLAY 0.872340 (-2000 2725);
PAINT ORANGE (-2000 2725);
DISPLAY INVISIBLE (-2000 2725);
FORCEPROP 1 LAST BODY_TYPE PLUMBING
J 2
(-1675 2900);
DISPLAY 0.872340 (-1675 2900);
PAINT GREEN (-1675 2900);
DISPLAY INVISIBLE (-1675 2900);
FORCEPROP 2 LAST CDS_LIB mstr_standard
J 0
(-1675 2850);
PAINT ORANGE (-1675 2850);
DISPLAY INVISIBLE (-1675 2850);
FORCEADD TAP..1
R 2
(-1675 2450);
FORCEPROP 3 LASTPIN (-1625 2450) SIG_NAME P3E_OCP_CPU0_PE3_C_TXP<0>
J 0
(-1615 2460);
DISPLAY 0.659574 (-1615 2460);
PAINT MONO (-1615 2460);
DISPLAY INVISIBLE (-1615 2460);
FORCEPROP 1 LASTPIN (-1625 2450) BN 0
J 2
(-1613 2458);
DISPLAY 0.617021 (-1613 2458);
PAINT GREEN (-1613 2458);
FORCEPROP 1 LAST PATH I158
J 2
(-1673 2450);
DISPLAY 0.872340 (-1673 2450);
PAINT GREEN (-1673 2450);
DISPLAY INVISIBLE (-1673 2450);
FORCEPROP 1 LAST HDL_TAP TRUE
J 2
(-2000 2325);
DISPLAY 0.872340 (-2000 2325);
PAINT ORANGE (-2000 2325);
DISPLAY INVISIBLE (-2000 2325);
FORCEPROP 1 LAST BODY_TYPE PLUMBING
J 2
(-1675 2500);
DISPLAY 0.872340 (-1675 2500);
PAINT GREEN (-1675 2500);
DISPLAY INVISIBLE (-1675 2500);
FORCEPROP 2 LAST CDS_LIB mstr_standard
J 0
(-1675 2450);
PAINT ORANGE (-1675 2450);
DISPLAY INVISIBLE (-1675 2450);
FORCEADD OFFPAGE..1
(-1700 2200);
FORCEPROP 2 LAST $XR0 114 
J 0
(-2012 2200);
DISPLAY 0.638298 (-2012 2200);
PAINT MONO (-2012 2200);
FORCEPROP 2 LAST PATH I159
J 0
(-2000 2250);
DISPLAY 1.021277 (-2000 2250);
PAINT ORANGE (-2000 2250);
DISPLAY INVISIBLE (-2000 2250);
FORCEPROP 1 LAST COMMENT_BODY TRUE
J 0
(-1575 2100);
DISPLAY 0.872340 (-1575 2100);
PAINT GREEN (-1575 2100);
DISPLAY INVISIBLE (-1575 2100);
FORCEPROP 1 LAST OFFPAGE TRUE
J 0
(-1375 2075);
DISPLAY 0.872340 (-1375 2075);
PAINT GREEN (-1375 2075);
DISPLAY INVISIBLE (-1375 2075);
FORCEPROP 2 LAST CDS_LIB mstr_standard
J 0
(-1700 2200);
PAINT ORANGE (-1700 2200);
DISPLAY INVISIBLE (-1700 2200);
FORCEADD OFFPAGE..1
(-1700 2250);
FORCEPROP 2 LAST $XR0 114 
J 0
(-2012 2250);
DISPLAY 0.638298 (-2012 2250);
PAINT MONO (-2012 2250);
FORCEPROP 2 LAST PATH I160
J 0
(-2000 2300);
DISPLAY 1.021277 (-2000 2300);
PAINT ORANGE (-2000 2300);
DISPLAY INVISIBLE (-2000 2300);
FORCEPROP 1 LAST COMMENT_BODY TRUE
J 0
(-1575 2150);
DISPLAY 0.872340 (-1575 2150);
PAINT GREEN (-1575 2150);
DISPLAY INVISIBLE (-1575 2150);
FORCEPROP 1 LAST OFFPAGE TRUE
J 0
(-1375 2125);
DISPLAY 0.872340 (-1375 2125);
PAINT GREEN (-1375 2125);
DISPLAY INVISIBLE (-1375 2125);
FORCEPROP 2 LAST CDS_LIB mstr_standard
J 0
(-1700 2250);
PAINT ORANGE (-1700 2250);
DISPLAY INVISIBLE (-1700 2250);
FORCEADD GND..1
(-725 1850);
FORCEPROP 3 LASTPIN (-725 1900) SIG_NAME GND\g
J 0
(-715 1910);
DISPLAY 0.659574 (-715 1910);
PAINT MONO (-715 1910);
DISPLAY INVISIBLE (-715 1910);
FORCEPROP 1 LAST HDL_POWER GND
J 0
(-725 2000);
DISPLAY 0.872340 (-725 2000);
PAINT GREEN (-725 2000);
DISPLAY INVISIBLE (-725 2000);
FORCEPROP 1 LAST PATH I162
J 0
(-650 1850);
DISPLAY 0.872340 (-650 1850);
PAINT AQUA (-650 1850);
DISPLAY INVISIBLE (-650 1850);
FORCEPROP 1 LAST BODY_TYPE PLUMBING
J 0
(-770 1807);
DISPLAY 0.340426 (-770 1807);
PAINT GREEN (-770 1807);
DISPLAY INVISIBLE (-770 1807);
FORCEPROP 1 LAST SIZE 1B
J 0
(-650 1800);
DISPLAY 0.872340 (-650 1800);
PAINT AQUA (-650 1800);
DISPLAY INVISIBLE (-650 1800);
FORCEPROP 2 LAST CDS_LIB mstr_symbols
J 0
(-725 1850);
PAINT ORANGE (-725 1850);
DISPLAY INVISIBLE (-725 1850);
FORCEPROP 1 LAST VOLTAGE 0
J 0
(-725 1850);
PAINT SKYBLUE (-725 1850);
DISPLAY INVISIBLE (-725 1850);
FORCEADD TAP..1
R 2
(-1950 2600);
FORCEPROP 3 LASTPIN (-1900 2600) SIG_NAME P3E_OCP_CPU0_PE3_C_TXN<1>
J 0
(-1890 2610);
DISPLAY 0.659574 (-1890 2610);
PAINT MONO (-1890 2610);
DISPLAY INVISIBLE (-1890 2610);
FORCEPROP 1 LASTPIN (-1900 2600) BN 1
J 2
(-1888 2608);
DISPLAY 0.617021 (-1888 2608);
PAINT GREEN (-1888 2608);
FORCEPROP 1 LAST PATH I164
J 2
(-1948 2600);
DISPLAY 0.872340 (-1948 2600);
PAINT GREEN (-1948 2600);
DISPLAY INVISIBLE (-1948 2600);
FORCEPROP 1 LAST HDL_TAP TRUE
J 2
(-2275 2475);
DISPLAY 0.872340 (-2275 2475);
PAINT ORANGE (-2275 2475);
DISPLAY INVISIBLE (-2275 2475);
FORCEPROP 1 LAST BODY_TYPE PLUMBING
J 2
(-1950 2650);
DISPLAY 0.872340 (-1950 2650);
PAINT GREEN (-1950 2650);
DISPLAY INVISIBLE (-1950 2650);
FORCEPROP 2 LAST CDS_LIB mstr_standard
J 0
(-1950 2600);
PAINT ORANGE (-1950 2600);
DISPLAY INVISIBLE (-1950 2600);
FORCEADD TAP..1
R 2
(-1950 2800);
FORCEPROP 3 LASTPIN (-1900 2800) SIG_NAME P3E_OCP_CPU0_PE3_C_TXN<2>
J 0
(-1890 2810);
DISPLAY 0.659574 (-1890 2810);
PAINT MONO (-1890 2810);
DISPLAY INVISIBLE (-1890 2810);
FORCEPROP 1 LASTPIN (-1900 2800) BN 2
J 2
(-1888 2808);
DISPLAY 0.617021 (-1888 2808);
PAINT GREEN (-1888 2808);
FORCEPROP 1 LAST PATH I165
J 2
(-1948 2800);
DISPLAY 0.872340 (-1948 2800);
PAINT GREEN (-1948 2800);
DISPLAY INVISIBLE (-1948 2800);
FORCEPROP 1 LAST HDL_TAP TRUE
J 2
(-2275 2675);
DISPLAY 0.872340 (-2275 2675);
PAINT ORANGE (-2275 2675);
DISPLAY INVISIBLE (-2275 2675);
FORCEPROP 1 LAST BODY_TYPE PLUMBING
J 2
(-1950 2850);
DISPLAY 0.872340 (-1950 2850);
PAINT GREEN (-1950 2850);
DISPLAY INVISIBLE (-1950 2850);
FORCEPROP 2 LAST CDS_LIB mstr_standard
J 0
(-1950 2800);
PAINT ORANGE (-1950 2800);
DISPLAY INVISIBLE (-1950 2800);
FORCEADD TAP..1
R 2
(-1950 3000);
FORCEPROP 3 LASTPIN (-1900 3000) SIG_NAME P3E_OCP_CPU0_PE3_C_TXN<3>
J 0
(-1890 3010);
DISPLAY 0.659574 (-1890 3010);
PAINT MONO (-1890 3010);
DISPLAY INVISIBLE (-1890 3010);
FORCEPROP 1 LASTPIN (-1900 3000) BN 3
J 2
(-1888 3008);
DISPLAY 0.617021 (-1888 3008);
PAINT GREEN (-1888 3008);
FORCEPROP 1 LAST PATH I166
J 2
(-1948 3000);
DISPLAY 0.872340 (-1948 3000);
PAINT GREEN (-1948 3000);
DISPLAY INVISIBLE (-1948 3000);
FORCEPROP 1 LAST HDL_TAP TRUE
J 2
(-2275 2875);
DISPLAY 0.872340 (-2275 2875);
PAINT ORANGE (-2275 2875);
DISPLAY INVISIBLE (-2275 2875);
FORCEPROP 1 LAST BODY_TYPE PLUMBING
J 2
(-1950 3050);
DISPLAY 0.872340 (-1950 3050);
PAINT GREEN (-1950 3050);
DISPLAY INVISIBLE (-1950 3050);
FORCEPROP 2 LAST CDS_LIB mstr_standard
J 0
(-1950 3000);
PAINT ORANGE (-1950 3000);
DISPLAY INVISIBLE (-1950 3000);
FORCEADD TAP..1
R 2
(-1950 2400);
FORCEPROP 3 LASTPIN (-1900 2400) SIG_NAME P3E_OCP_CPU0_PE3_C_TXN<0>
J 0
(-1890 2410);
DISPLAY 0.659574 (-1890 2410);
PAINT MONO (-1890 2410);
DISPLAY INVISIBLE (-1890 2410);
FORCEPROP 1 LASTPIN (-1900 2400) BN 0
J 2
(-1888 2408);
DISPLAY 0.617021 (-1888 2408);
PAINT GREEN (-1888 2408);
FORCEPROP 1 LAST PATH I167
J 2
(-1948 2400);
DISPLAY 0.872340 (-1948 2400);
PAINT GREEN (-1948 2400);
DISPLAY INVISIBLE (-1948 2400);
FORCEPROP 1 LAST HDL_TAP TRUE
J 2
(-2275 2275);
DISPLAY 0.872340 (-2275 2275);
PAINT ORANGE (-2275 2275);
DISPLAY INVISIBLE (-2275 2275);
FORCEPROP 1 LAST BODY_TYPE PLUMBING
J 2
(-1950 2450);
DISPLAY 0.872340 (-1950 2450);
PAINT GREEN (-1950 2450);
DISPLAY INVISIBLE (-1950 2450);
FORCEPROP 2 LAST CDS_LIB mstr_standard
J 0
(-1950 2400);
PAINT ORANGE (-1950 2400);
DISPLAY INVISIBLE (-1950 2400);
FORCEADD OFFPAGE..5
(-1700 2100);
FORCEPROP 2 LAST $XR0 250 
J 0
(-1955 2100);
DISPLAY 0.638298 (-1955 2100);
PAINT MONO (-1955 2100);
FORCEPROP 2 LAST PATH I168
J 0
(-1650 2175);
DISPLAY 1.021277 (-1650 2175);
PAINT ORANGE (-1650 2175);
DISPLAY INVISIBLE (-1650 2175);
FORCEPROP 1 LAST COMMENT_BODY TRUE
J 0
(-1600 2025);
DISPLAY 0.872340 (-1600 2025);
PAINT GREEN (-1600 2025);
DISPLAY INVISIBLE (-1600 2025);
FORCEPROP 1 LAST OFFPAGE TRUE
J 0
(-1375 1975);
DISPLAY 0.872340 (-1375 1975);
PAINT GREEN (-1375 1975);
DISPLAY INVISIBLE (-1375 1975);
FORCEPROP 2 LAST CDS_LIB mstr_standard
J 0
(-1700 2100);
PAINT ORANGE (-1700 2100);
DISPLAY INVISIBLE (-1700 2100);
FORCEADD GND..1
(1950 4100);
FORCEPROP 3 LASTPIN (1950 4150) SIG_NAME GND\g
J 0
(1960 4160);
DISPLAY 0.659574 (1960 4160);
PAINT MONO (1960 4160);
DISPLAY INVISIBLE (1960 4160);
FORCEPROP 1 LAST VOLTAGE 0
J 0
(1950 4100);
PAINT SKYBLUE (1950 4100);
DISPLAY INVISIBLE (1950 4100);
FORCEPROP 1 LAST HDL_POWER GND
J 0
(1950 4250);
DISPLAY 0.872340 (1950 4250);
PAINT GREEN (1950 4250);
DISPLAY INVISIBLE (1950 4250);
FORCEPROP 1 LAST BODY_TYPE PLUMBING
J 0
(1905 4057);
DISPLAY 0.340426 (1905 4057);
PAINT GREEN (1905 4057);
DISPLAY INVISIBLE (1905 4057);
FORCEPROP 1 LAST SIZE 1B
J 0
(2025 4050);
DISPLAY 0.872340 (2025 4050);
PAINT AQUA (2025 4050);
DISPLAY INVISIBLE (2025 4050);
FORCEPROP 2 LAST CDS_LIB mstr_symbols
J 0
(1950 4100);
PAINT ORANGE (1950 4100);
DISPLAY INVISIBLE (1950 4100);
FORCEPROP 1 LAST PATH I169
J 0
(2025 4100);
DISPLAY 0.872340 (2025 4100);
PAINT AQUA (2025 4100);
DISPLAY INVISIBLE (2025 4100);
FORCEADD P3V3_STBY..1
(1950 4900);
FORCEPROP 3 LASTPIN (1950 4850) SIG_NAME P3V3_STBY\g
J 0
(1960 4860);
DISPLAY 0.659574 (1960 4860);
PAINT MONO (1960 4860);
DISPLAY INVISIBLE (1960 4860);
FORCEPROP 1 LAST PATH I171
J 0
(1995 4902);
DISPLAY 0.340426 (1995 4902);
PAINT GREEN (1995 4902);
DISPLAY INVISIBLE (1995 4902);
FORCEPROP 1 LAST SIZE 1B
J 0
(1995 4922);
DISPLAY 0.340426 (1995 4922);
PAINT GREEN (1995 4922);
DISPLAY INVISIBLE (1995 4922);
FORCEPROP 1 LAST BODY_TYPE PLUMBING
J 0
(1905 4857);
DISPLAY 0.340426 (1905 4857);
PAINT GREEN (1905 4857);
DISPLAY INVISIBLE (1905 4857);
FORCEPROP 1 LAST HDL_POWER P3V3_STBY
J 0
(1650 4775);
DISPLAY 0.872340 (1650 4775);
PAINT ORANGE (1650 4775);
DISPLAY INVISIBLE (1650 4775);
FORCEPROP 1 LAST VOLTAGE 3.3V
J 0
(1905 4857);
DISPLAY 0.340426 (1905 4857);
PAINT SKYBLUE (1905 4857);
DISPLAY INVISIBLE (1905 4857);
FORCEPROP 2 LAST CDS_LIB mstr_symbols
J 0
(1950 4900);
PAINT MONO (1950 4900);
DISPLAY INVISIBLE (1950 4900);
FORCEADD RES..2
(1950 4675);
FORCEPROP 1 LAST TOLERANCE 1%
J 0
(2045 4700);
DISPLAY 0.617021 (2045 4700);
PAINT SKYBLUE (2045 4700);
FORCEPROP 1 LAST VALUE 10.0K
J 0
(2045 4750);
DISPLAY 0.617021 (2045 4750);
PAINT SKYBLUE (2045 4750);
FORCEPROP 1 LASTPIN (1950 4775) $PN 1
J 0
(1955 4737);
DISPLAY 0.787234 (1955 4737);
PAINT ORANGE (1955 4737);
FORCEPROP 1 LAST PART_NUMBER G21796-016
R 1
J 0
(1890 4550);
DISPLAY 0.617021 (1890 4550);
PAINT BLUE (1890 4550);
FORCEPROP 1 LAST LOCATION R2W1
J 0
(2045 4800);
DISPLAY 0.617021 (2045 4800);
PAINT AQUA (2045 4800);
FORCEPROP 1 LAST WATTAGE 1/16W
J 0
(2040 4650);
DISPLAY 0.617021 (2040 4650);
PAINT SKYBLUE (2040 4650);
FORCEPROP 1 LAST PACK_TYPE 0402
J 0
(2040 4550);
DISPLAY 0.617021 (2040 4550);
PAINT SKYBLUE (2040 4550);
FORCEPROP 1 LASTPIN (1950 4575) $PN 2
J 0
(1955 4585);
DISPLAY 0.787234 (1955 4585);
PAINT ORANGE (1955 4585);
FORCEPROP 1 LAST MATERIAL CHIP
J 0
(2040 4600);
DISPLAY 0.617021 (2040 4600);
PAINT SKYBLUE (2040 4600);
FORCEPROP 2 LAST BOM_COST PROC_SIDEBAND
J 0
(1950 4675);
PAINT WHITE (1950 4675);
DISPLAY INVISIBLE (1950 4675);
FORCEPROP 2 LAST ROOM CPU0
J 0
(1975 4450);
PAINT WHITE (1975 4450);
DISPLAY INVISIBLE (1975 4450);
FORCEPROP 1 LAST PATH I174
J 0
(2000 4850);
DISPLAY 0.978723 (2000 4850);
PAINT WHITE (2000 4850);
DISPLAY INVISIBLE (2000 4850);
FORCEPROP 2 LAST CDS_LIB mstr_discrete
J 0
(1950 4675);
PAINT MONO (1950 4675);
DISPLAY INVISIBLE (1950 4675);
FORCEPROP 0 LAST SEC 1
J 0
(2050 4850);
DISPLAY 0.680851 (2050 4850);
PAINT MONO (2050 4850);
DISPLAY INVISIBLE (2050 4850);
FORCEPROP 2 LAST SEC_TYPE 0402
J 0
(2000 4900);
DISPLAY 1.021277 (2000 4900);
PAINT ORANGE (2000 4900);
DISPLAY INVISIBLE (2000 4900);
FORCEADD 887R2F-L-GP..1
(1950 4325);
FORCEPROP 2 LASTPIN (1950 4450) $PN 1
R 1
J 0
(1940 4460);
DISPLAY 0.808511 (1940 4460);
PAINT ORANGE (1940 4460);
FORCEPROP 2 LASTPIN (1950 4200) $PN 2
R 1
J 2
(1940 4190);
DISPLAY 0.808511 (1940 4190);
PAINT ORANGE (1940 4190);
FORCEPROP 2 LAST RATED 1/16W
J 0
(1975 4225);
DISPLAY 0.638298 (1975 4225);
PAINT GREEN (1975 4225);
FORCEPROP 2 LAST TOLERANCE 1%
J 0
(1975 4275);
DISPLAY 0.638298 (1975 4275);
PAINT GREEN (1975 4275);
FORCEPROP 2 LAST ATTRIBUTE 887OHM
J 0
(1975 4325);
DISPLAY 0.638298 (1975 4325);
PAINT GREEN (1975 4325);
FORCEPROP 1 LAST VALUE 887R2F-L-GP
J 0
(1975 4375);
DISPLAY 0.617021 (1975 4375);
PAINT GREEN (1975 4375);
FORCEPROP 1 LAST LOCATION R2R8
J 0
(1975 4425);
DISPLAY 0.617021 (1975 4425);
PAINT GREEN (1975 4425);
FORCEPROP 2 LAST PACK_SIZE 0402
J 0
(1975 4175);
DISPLAY 0.638298 (1975 4175);
PAINT GREEN (1975 4175);
FORCEPROP 1 LAST CDS_LMAN_SYM_OUTLINE -50,75,50,-75
J 0
(1950 4325);
DISPLAY 0.468085 (1950 4325);
PAINT GREEN (1950 4325);
DISPLAY INVISIBLE (1950 4325);
FORCEPROP 2 LAST CDS_LIB w_hdl
J 0
(1950 4325);
DISPLAY INVISIBLE (1950 4325);
FORCEPROP 1 LAST PART_NUMBER 64.88705.6DL
J 0
(1950 4325);
DISPLAY 0.617021 (1950 4325);
PAINT GREEN (1950 4325);
DISPLAY INVISIBLE (1950 4325);
FORCEPROP 2 LAST SEC_TYPE SMD-RG
J 0
(1975 4475);
DISPLAY 1.021277 (1975 4475);
PAINT ORANGE (1975 4475);
DISPLAY INVISIBLE (1975 4475);
FORCEPROP 2 LAST SEC 1
J 0
(1975 4475);
DISPLAY 0.680851 (1975 4475);
PAINT MONO (1975 4475);
DISPLAY INVISIBLE (1975 4475);
FORCEPROP 1 LAST PACK_TYPE SMD-RG
J 0
(1950 4325);
DISPLAY 0.617021 (1950 4325);
PAINT GREEN (1950 4325);
DISPLAY INVISIBLE (1950 4325);
FORCEPROP 1 LAST PATH I175
J 0
(1950 4325);
DISPLAY 0.617021 (1950 4325);
PAINT GREEN (1950 4325);
DISPLAY INVISIBLE (1950 4325);
FORCEADD OFFPAGE..2
(2525 3950);
FORCEPROP 2 LAST $XR0 32 
J 0
(2714 3950);
DISPLAY 0.638298 (2714 3950);
PAINT MONO (2714 3950);
FORCEPROP 2 LAST PATH I44
J 2
(2325 4000);
DISPLAY 1.021277 (2325 4000);
PAINT ORANGE (2325 4000);
DISPLAY INVISIBLE (2325 4000);
FORCEPROP 1 LAST COMMENT_BODY TRUE
J 0
(2480 3855);
DISPLAY 0.872340 (2480 3855);
PAINT GREEN (2480 3855);
DISPLAY INVISIBLE (2480 3855);
FORCEPROP 1 LAST OFFPAGE TRUE
J 0
(2850 3825);
DISPLAY 0.872340 (2850 3825);
PAINT GREEN (2850 3825);
DISPLAY INVISIBLE (2850 3825);
FORCEPROP 2 LAST CDS_LIB mstr_standard
J 0
(2525 3950);
PAINT ORANGE (2525 3950);
DISPLAY INVISIBLE (2525 3950);
FORCEADD OFFPAGE..2
(2525 4025);
FORCEPROP 2 LAST $XR0 32 
J 0
(2714 4025);
DISPLAY 0.638298 (2714 4025);
PAINT MONO (2714 4025);
FORCEPROP 2 LAST PATH I45
J 2
(2325 4075);
DISPLAY 1.021277 (2325 4075);
PAINT ORANGE (2325 4075);
DISPLAY INVISIBLE (2325 4075);
FORCEPROP 1 LAST COMMENT_BODY TRUE
J 0
(2480 3930);
DISPLAY 0.872340 (2480 3930);
PAINT GREEN (2480 3930);
DISPLAY INVISIBLE (2480 3930);
FORCEPROP 1 LAST OFFPAGE TRUE
J 0
(2850 3900);
DISPLAY 0.872340 (2850 3900);
PAINT GREEN (2850 3900);
DISPLAY INVISIBLE (2850 3900);
FORCEPROP 2 LAST CDS_LIB mstr_standard
J 0
(2525 4025);
PAINT ORANGE (2525 4025);
DISPLAY INVISIBLE (2525 4025);
FORCEADD TAP..1
(1550 3950);
FORCEPROP 3 LASTPIN (1500 3950) SIG_NAME P3E_CPU0_PE3_OCP_RXP<7>
J 0
(1510 3960);
DISPLAY 0.659574 (1510 3960);
PAINT MONO (1510 3960);
DISPLAY INVISIBLE (1510 3960);
FORCEPROP 1 LASTPIN (1500 3950) BN 7
J 0
(1488 3958);
DISPLAY 0.617021 (1488 3958);
PAINT GREEN (1488 3958);
FORCEPROP 1 LAST PATH I46
J 0
(1548 3950);
DISPLAY 0.872340 (1548 3950);
PAINT GREEN (1548 3950);
DISPLAY INVISIBLE (1548 3950);
FORCEPROP 1 LAST HDL_TAP TRUE
J 0
(1875 3825);
DISPLAY 0.872340 (1875 3825);
PAINT ORANGE (1875 3825);
DISPLAY INVISIBLE (1875 3825);
FORCEPROP 1 LAST BODY_TYPE PLUMBING
J 0
(1550 4000);
DISPLAY 0.872340 (1550 4000);
PAINT GREEN (1550 4000);
DISPLAY INVISIBLE (1550 4000);
FORCEPROP 2 LAST CDS_LIB mstr_standard
J 0
(1550 3950);
PAINT ORANGE (1550 3950);
DISPLAY INVISIBLE (1550 3950);
FORCEADD TAP..1
(1750 3900);
FORCEPROP 3 LASTPIN (1700 3900) SIG_NAME P3E_CPU0_PE3_OCP_RXN<7>
J 0
(1710 3910);
DISPLAY 0.659574 (1710 3910);
PAINT MONO (1710 3910);
DISPLAY INVISIBLE (1710 3910);
FORCEPROP 1 LASTPIN (1700 3900) BN 7
J 0
(1688 3908);
DISPLAY 0.617021 (1688 3908);
PAINT GREEN (1688 3908);
FORCEPROP 1 LAST PATH I47
J 0
(1748 3900);
DISPLAY 0.872340 (1748 3900);
PAINT GREEN (1748 3900);
DISPLAY INVISIBLE (1748 3900);
FORCEPROP 1 LAST HDL_TAP TRUE
J 0
(2075 3775);
DISPLAY 0.872340 (2075 3775);
PAINT ORANGE (2075 3775);
DISPLAY INVISIBLE (2075 3775);
FORCEPROP 1 LAST BODY_TYPE PLUMBING
J 0
(1750 3950);
DISPLAY 0.872340 (1750 3950);
PAINT GREEN (1750 3950);
DISPLAY INVISIBLE (1750 3950);
FORCEPROP 2 LAST CDS_LIB mstr_standard
J 0
(1750 3900);
PAINT ORANGE (1750 3900);
DISPLAY INVISIBLE (1750 3900);
FORCEADD TAP..1
(1750 3100);
FORCEPROP 3 LASTPIN (1700 3100) SIG_NAME P3E_CPU0_PE3_OCP_RXN<3>
J 0
(1710 3110);
DISPLAY 0.659574 (1710 3110);
PAINT MONO (1710 3110);
DISPLAY INVISIBLE (1710 3110);
FORCEPROP 1 LASTPIN (1700 3100) BN 3
J 0
(1688 3108);
DISPLAY 0.617021 (1688 3108);
PAINT GREEN (1688 3108);
FORCEPROP 1 LAST PATH I50
J 0
(1748 3100);
DISPLAY 0.872340 (1748 3100);
PAINT GREEN (1748 3100);
DISPLAY INVISIBLE (1748 3100);
FORCEPROP 1 LAST HDL_TAP TRUE
J 0
(2075 2975);
DISPLAY 0.872340 (2075 2975);
PAINT ORANGE (2075 2975);
DISPLAY INVISIBLE (2075 2975);
FORCEPROP 1 LAST BODY_TYPE PLUMBING
J 0
(1750 3150);
DISPLAY 0.872340 (1750 3150);
PAINT GREEN (1750 3150);
DISPLAY INVISIBLE (1750 3150);
FORCEPROP 2 LAST CDS_LIB mstr_standard
J 0
(1750 3100);
PAINT ORANGE (1750 3100);
DISPLAY INVISIBLE (1750 3100);
FORCEADD TAP..1
(1550 3150);
FORCEPROP 3 LASTPIN (1500 3150) SIG_NAME P3E_CPU0_PE3_OCP_RXP<3>
J 0
(1510 3160);
DISPLAY 0.659574 (1510 3160);
PAINT MONO (1510 3160);
DISPLAY INVISIBLE (1510 3160);
FORCEPROP 1 LASTPIN (1500 3150) BN 3
J 0
(1488 3158);
DISPLAY 0.617021 (1488 3158);
PAINT GREEN (1488 3158);
FORCEPROP 1 LAST PATH I51
J 0
(1548 3150);
DISPLAY 0.872340 (1548 3150);
PAINT GREEN (1548 3150);
DISPLAY INVISIBLE (1548 3150);
FORCEPROP 1 LAST HDL_TAP TRUE
J 0
(1875 3025);
DISPLAY 0.872340 (1875 3025);
PAINT ORANGE (1875 3025);
DISPLAY INVISIBLE (1875 3025);
FORCEPROP 1 LAST BODY_TYPE PLUMBING
J 0
(1550 3200);
DISPLAY 0.872340 (1550 3200);
PAINT GREEN (1550 3200);
DISPLAY INVISIBLE (1550 3200);
FORCEPROP 2 LAST CDS_LIB mstr_standard
J 0
(1550 3150);
PAINT ORANGE (1550 3150);
DISPLAY INVISIBLE (1550 3150);
FORCEADD P12V_STBY..1
(-1000 4375);
FORCEPROP 3 LASTPIN (-1000 4325) SIG_NAME P12V_STBY\g
J 0
(-990 4335);
DISPLAY 0.659574 (-990 4335);
PAINT MONO (-990 4335);
DISPLAY INVISIBLE (-990 4335);
FORCEPROP 1 LAST HDL_POWER P12V_STBY
J 0
(-1300 4250);
DISPLAY 0.872340 (-1300 4250);
PAINT ORANGE (-1300 4250);
DISPLAY INVISIBLE (-1300 4250);
FORCEPROP 1 LAST PATH I70
J 0
(-955 4377);
DISPLAY 0.340426 (-955 4377);
PAINT GREEN (-955 4377);
DISPLAY INVISIBLE (-955 4377);
FORCEPROP 1 LAST BODY_TYPE PLUMBING
J 0
(-1045 4332);
DISPLAY 0.340426 (-1045 4332);
PAINT GREEN (-1045 4332);
DISPLAY INVISIBLE (-1045 4332);
FORCEPROP 2 LAST CDS_LIB mstr_symbols
J 0
(-1000 4375);
PAINT ORANGE (-1000 4375);
DISPLAY INVISIBLE (-1000 4375);
FORCEPROP 1 LAST SIZE 1B
J 0
(-955 4397);
DISPLAY 0.340426 (-955 4397);
PAINT GREEN (-955 4397);
DISPLAY INVISIBLE (-955 4397);
FORCEPROP 1 LAST VOLTAGE 12.0V
J 0
(-1045 4332);
DISPLAY 0.340426 (-1045 4332);
PAINT SKYBLUE (-1045 4332);
DISPLAY INVISIBLE (-1045 4332);
FORCEADD TAP..1
R 2
(-1675 3850);
FORCEPROP 3 LASTPIN (-1625 3850) SIG_NAME P3E_OCP_CPU0_PE3_C_TXP<7>
J 0
(-1615 3860);
DISPLAY 0.659574 (-1615 3860);
PAINT MONO (-1615 3860);
DISPLAY INVISIBLE (-1615 3860);
FORCEPROP 1 LASTPIN (-1625 3850) BN 7
J 2
(-1613 3858);
DISPLAY 0.617021 (-1613 3858);
PAINT GREEN (-1613 3858);
FORCEPROP 1 LAST PATH I87
J 2
(-1673 3850);
DISPLAY 0.872340 (-1673 3850);
PAINT GREEN (-1673 3850);
DISPLAY INVISIBLE (-1673 3850);
FORCEPROP 1 LAST HDL_TAP TRUE
J 2
(-2000 3725);
DISPLAY 0.872340 (-2000 3725);
PAINT ORANGE (-2000 3725);
DISPLAY INVISIBLE (-2000 3725);
FORCEPROP 1 LAST BODY_TYPE PLUMBING
J 2
(-1675 3900);
DISPLAY 0.872340 (-1675 3900);
PAINT GREEN (-1675 3900);
DISPLAY INVISIBLE (-1675 3900);
FORCEPROP 2 LAST CDS_LIB mstr_standard
J 0
(-1675 3850);
PAINT ORANGE (-1675 3850);
DISPLAY INVISIBLE (-1675 3850);
FORCEADD TAP..1
R 2
(-1675 3650);
FORCEPROP 3 LASTPIN (-1625 3650) SIG_NAME P3E_OCP_CPU0_PE3_C_TXP<6>
J 0
(-1615 3660);
DISPLAY 0.659574 (-1615 3660);
PAINT MONO (-1615 3660);
DISPLAY INVISIBLE (-1615 3660);
FORCEPROP 1 LASTPIN (-1625 3650) BN 6
J 2
(-1613 3658);
DISPLAY 0.617021 (-1613 3658);
PAINT GREEN (-1613 3658);
FORCEPROP 1 LAST PATH I88
J 2
(-1673 3650);
DISPLAY 0.872340 (-1673 3650);
PAINT GREEN (-1673 3650);
DISPLAY INVISIBLE (-1673 3650);
FORCEPROP 1 LAST HDL_TAP TRUE
J 2
(-2000 3525);
DISPLAY 0.872340 (-2000 3525);
PAINT ORANGE (-2000 3525);
DISPLAY INVISIBLE (-2000 3525);
FORCEPROP 1 LAST BODY_TYPE PLUMBING
J 2
(-1675 3700);
DISPLAY 0.872340 (-1675 3700);
PAINT GREEN (-1675 3700);
DISPLAY INVISIBLE (-1675 3700);
FORCEPROP 2 LAST CDS_LIB mstr_standard
J 0
(-1675 3650);
PAINT ORANGE (-1675 3650);
DISPLAY INVISIBLE (-1675 3650);
FORCEADD TAP..1
R 2
(-1675 3450);
FORCEPROP 3 LASTPIN (-1625 3450) SIG_NAME P3E_OCP_CPU0_PE3_C_TXP<5>
J 0
(-1615 3460);
DISPLAY 0.659574 (-1615 3460);
PAINT MONO (-1615 3460);
DISPLAY INVISIBLE (-1615 3460);
FORCEPROP 1 LASTPIN (-1625 3450) BN 5
J 2
(-1613 3458);
DISPLAY 0.617021 (-1613 3458);
PAINT GREEN (-1613 3458);
FORCEPROP 1 LAST PATH I89
J 2
(-1673 3450);
DISPLAY 0.872340 (-1673 3450);
PAINT GREEN (-1673 3450);
DISPLAY INVISIBLE (-1673 3450);
FORCEPROP 1 LAST HDL_TAP TRUE
J 2
(-2000 3325);
DISPLAY 0.872340 (-2000 3325);
PAINT ORANGE (-2000 3325);
DISPLAY INVISIBLE (-2000 3325);
FORCEPROP 1 LAST BODY_TYPE PLUMBING
J 2
(-1675 3500);
DISPLAY 0.872340 (-1675 3500);
PAINT GREEN (-1675 3500);
DISPLAY INVISIBLE (-1675 3500);
FORCEPROP 2 LAST CDS_LIB mstr_standard
J 0
(-1675 3450);
PAINT ORANGE (-1675 3450);
DISPLAY INVISIBLE (-1675 3450);
FORCEADD TAP..1
R 2
(-1675 3250);
FORCEPROP 3 LASTPIN (-1625 3250) SIG_NAME P3E_OCP_CPU0_PE3_C_TXP<4>
J 0
(-1615 3260);
DISPLAY 0.659574 (-1615 3260);
PAINT MONO (-1615 3260);
DISPLAY INVISIBLE (-1615 3260);
FORCEPROP 1 LASTPIN (-1625 3250) BN 4
J 2
(-1613 3258);
DISPLAY 0.617021 (-1613 3258);
PAINT GREEN (-1613 3258);
FORCEPROP 1 LAST PATH I90
J 2
(-1673 3250);
DISPLAY 0.872340 (-1673 3250);
PAINT GREEN (-1673 3250);
DISPLAY INVISIBLE (-1673 3250);
FORCEPROP 1 LAST HDL_TAP TRUE
J 2
(-2000 3125);
DISPLAY 0.872340 (-2000 3125);
PAINT ORANGE (-2000 3125);
DISPLAY INVISIBLE (-2000 3125);
FORCEPROP 1 LAST BODY_TYPE PLUMBING
J 2
(-1675 3300);
DISPLAY 0.872340 (-1675 3300);
PAINT GREEN (-1675 3300);
DISPLAY INVISIBLE (-1675 3300);
FORCEPROP 2 LAST CDS_LIB mstr_standard
J 0
(-1675 3250);
PAINT ORANGE (-1675 3250);
DISPLAY INVISIBLE (-1675 3250);
FORCEADD TAP..1
R 2
(-1950 3800);
FORCEPROP 3 LASTPIN (-1900 3800) SIG_NAME P3E_OCP_CPU0_PE3_C_TXN<7>
J 0
(-1890 3810);
DISPLAY 0.659574 (-1890 3810);
PAINT MONO (-1890 3810);
DISPLAY INVISIBLE (-1890 3810);
FORCEPROP 1 LASTPIN (-1900 3800) BN 7
J 2
(-1888 3808);
DISPLAY 0.617021 (-1888 3808);
PAINT GREEN (-1888 3808);
FORCEPROP 1 LAST PATH I95
J 2
(-1948 3800);
DISPLAY 0.872340 (-1948 3800);
PAINT GREEN (-1948 3800);
DISPLAY INVISIBLE (-1948 3800);
FORCEPROP 1 LAST HDL_TAP TRUE
J 2
(-2275 3675);
DISPLAY 0.872340 (-2275 3675);
PAINT ORANGE (-2275 3675);
DISPLAY INVISIBLE (-2275 3675);
FORCEPROP 1 LAST BODY_TYPE PLUMBING
J 2
(-1950 3850);
DISPLAY 0.872340 (-1950 3850);
PAINT GREEN (-1950 3850);
DISPLAY INVISIBLE (-1950 3850);
FORCEPROP 2 LAST CDS_LIB mstr_standard
J 0
(-1950 3800);
PAINT ORANGE (-1950 3800);
DISPLAY INVISIBLE (-1950 3800);
FORCEADD TAP..1
R 2
(-1950 3600);
FORCEPROP 3 LASTPIN (-1900 3600) SIG_NAME P3E_OCP_CPU0_PE3_C_TXN<6>
J 0
(-1890 3610);
DISPLAY 0.659574 (-1890 3610);
PAINT MONO (-1890 3610);
DISPLAY INVISIBLE (-1890 3610);
FORCEPROP 1 LASTPIN (-1900 3600) BN 6
J 2
(-1888 3608);
DISPLAY 0.617021 (-1888 3608);
PAINT GREEN (-1888 3608);
FORCEPROP 1 LAST PATH I96
J 2
(-1948 3600);
DISPLAY 0.872340 (-1948 3600);
PAINT GREEN (-1948 3600);
DISPLAY INVISIBLE (-1948 3600);
FORCEPROP 1 LAST HDL_TAP TRUE
J 2
(-2275 3475);
DISPLAY 0.872340 (-2275 3475);
PAINT ORANGE (-2275 3475);
DISPLAY INVISIBLE (-2275 3475);
FORCEPROP 1 LAST BODY_TYPE PLUMBING
J 2
(-1950 3650);
DISPLAY 0.872340 (-1950 3650);
PAINT GREEN (-1950 3650);
DISPLAY INVISIBLE (-1950 3650);
FORCEPROP 2 LAST CDS_LIB mstr_standard
J 0
(-1950 3600);
PAINT ORANGE (-1950 3600);
DISPLAY INVISIBLE (-1950 3600);
FORCEADD TAP..1
R 2
(-1950 3400);
FORCEPROP 3 LASTPIN (-1900 3400) SIG_NAME P3E_OCP_CPU0_PE3_C_TXN<5>
J 0
(-1890 3410);
DISPLAY 0.659574 (-1890 3410);
PAINT MONO (-1890 3410);
DISPLAY INVISIBLE (-1890 3410);
FORCEPROP 1 LASTPIN (-1900 3400) BN 5
J 2
(-1888 3408);
DISPLAY 0.617021 (-1888 3408);
PAINT GREEN (-1888 3408);
FORCEPROP 1 LAST PATH I97
J 2
(-1948 3400);
DISPLAY 0.872340 (-1948 3400);
PAINT GREEN (-1948 3400);
DISPLAY INVISIBLE (-1948 3400);
FORCEPROP 1 LAST HDL_TAP TRUE
J 2
(-2275 3275);
DISPLAY 0.872340 (-2275 3275);
PAINT ORANGE (-2275 3275);
DISPLAY INVISIBLE (-2275 3275);
FORCEPROP 1 LAST BODY_TYPE PLUMBING
J 2
(-1950 3450);
DISPLAY 0.872340 (-1950 3450);
PAINT GREEN (-1950 3450);
DISPLAY INVISIBLE (-1950 3450);
FORCEPROP 2 LAST CDS_LIB mstr_standard
J 0
(-1950 3400);
PAINT ORANGE (-1950 3400);
DISPLAY INVISIBLE (-1950 3400);
FORCEADD TAP..1
R 2
(-1950 3200);
FORCEPROP 3 LASTPIN (-1900 3200) SIG_NAME P3E_OCP_CPU0_PE3_C_TXN<4>
J 0
(-1890 3210);
DISPLAY 0.659574 (-1890 3210);
PAINT MONO (-1890 3210);
DISPLAY INVISIBLE (-1890 3210);
FORCEPROP 1 LASTPIN (-1900 3200) BN 4
J 2
(-1888 3208);
DISPLAY 0.617021 (-1888 3208);
PAINT GREEN (-1888 3208);
FORCEPROP 1 LAST PATH I98
J 2
(-1948 3200);
DISPLAY 0.872340 (-1948 3200);
PAINT GREEN (-1948 3200);
DISPLAY INVISIBLE (-1948 3200);
FORCEPROP 1 LAST HDL_TAP TRUE
J 2
(-2275 3075);
DISPLAY 0.872340 (-2275 3075);
PAINT ORANGE (-2275 3075);
DISPLAY INVISIBLE (-2275 3075);
FORCEPROP 1 LAST BODY_TYPE PLUMBING
J 2
(-1950 3250);
DISPLAY 0.872340 (-1950 3250);
PAINT GREEN (-1950 3250);
DISPLAY INVISIBLE (-1950 3250);
FORCEPROP 2 LAST CDS_LIB mstr_standard
J 0
(-1950 3200);
PAINT ORANGE (-1950 3200);
DISPLAY INVISIBLE (-1950 3200);
FORCEADD OFFPAGE..1
(-3050 4075);
FORCEPROP 2 LAST $XR0 106 
J 0
(-3302 4075);
DISPLAY 0.638298 (-3302 4075);
PAINT MONO (-3302 4075);
FORCEPROP 2 LAST PATH I99
J 0
(-3000 4150);
DISPLAY 1.021277 (-3000 4150);
PAINT ORANGE (-3000 4150);
DISPLAY INVISIBLE (-3000 4150);
FORCEPROP 1 LAST COMMENT_BODY TRUE
J 0
(-2925 3975);
DISPLAY 0.872340 (-2925 3975);
PAINT GREEN (-2925 3975);
DISPLAY INVISIBLE (-2925 3975);
FORCEPROP 1 LAST OFFPAGE TRUE
J 0
(-2725 3950);
DISPLAY 0.872340 (-2725 3950);
PAINT GREEN (-2725 3950);
DISPLAY INVISIBLE (-2725 3950);
FORCEPROP 2 LAST CDS_LIB mstr_standard
J 0
(-3050 4075);
PAINT ORANGE (-3050 4075);
DISPLAY INVISIBLE (-3050 4075);
FORCEADD DESIGN_NOTE..1
(525 4625);
FORCEPROP 0 LAST L2 12MM HT CONNECTOR IN BOM
J 0
(325 4425);
DISPLAY 1.021277 (325 4425);
PAINT ORANGE (325 4425);
FORCEPROP 0 LAST L1 13MM HT CONNECTOR IN SCHEMATIC
J 0
(325 4500);
DISPLAY 1.021277 (325 4500);
PAINT ORANGE (325 4500);
FORCEPROP 1 LAST COMMENT_BODY TRUE
J 0
(550 4725);
DISPLAY 0.978723 (550 4725);
PAINT ORANGE (550 4725);
DISPLAY INVISIBLE (550 4725);
FORCEPROP 2 LAST CDS_LIB mstr_symbols
J 0
(525 4625);
PAINT ORANGE (525 4625);
DISPLAY INVISIBLE (525 4625);
FORCEADD DESIGN_NOTE..1
(1500 5400);
FORCEPROP 0 LAST L1 SWAPPED 15:8 WITH 7:0 ON 120-PIN CONNECTOR
J 0
(1300 5250);
DISPLAY 1.021277 (1300 5250);
PAINT ORANGE (1300 5250);
FORCEPROP 0 LAST L2 TO ELIMINATE ROUTING CROSSOVER.
J 0
(1300 5150);
DISPLAY 1.021277 (1300 5150);
PAINT ORANGE (1300 5150);
FORCEPROP 2 LAST CDS_LIB mstr_symbols
J 0
(1500 5400);
PAINT ORANGE (1500 5400);
DISPLAY INVISIBLE (1500 5400);
FORCEPROP 1 LAST COMMENT_BODY TRUE
J 0
(1525 5500);
DISPLAY 0.978723 (1525 5500);
PAINT ORANGE (1525 5500);
DISPLAY INVISIBLE (1525 5500);
FORCEADD INTEL_CORP_BPAGE..1
(4050 475);
FORCEPROP 1 LAST CDS_CON_LAST_MODIFIED Fri Jun 16 17:49:09 2017
J 0
(2625 800);
PAINT ORANGE (2625 800);
DISPLAY INVISIBLE (2625 800);
FORCEPROP 1 LAST CUSTOM_TXT_CDS <CURRENT_DESIGN_SHEET> OF <TOTAL_DESIGN_SHEETS>
J 0
(3550 500);
PAINT ORANGE (3550 500);
FORCEPROP 1 LAST CUSTOM_TXT_CDS <CON_LAST_MODIFIED>
J 0
(50 575);
PAINT ORANGE (50 575);
FORCEPROP 2 LAST CUSTOM_TXT_CDS <XR_PAGE_TITLE>
J 0
(-3840 5725);
DISPLAY 0.638298 (-3840 5725);
PAINT PINK (-3840 5725);
DISPLAY INVISIBLE (-3840 5725);
FORCEPROP 1 LAST SCH_TITLE OCP MODULE CONN B
J 0
(-3900 525);
DISPLAY 1.212766 (-3900 525);
PAINT ORANGE (-3900 525);
FORCEPROP 1 LAST COMMENT_BODY TRUE
J 0
(4062 487);
DISPLAY 0.468085 (4062 487);
PAINT GREEN (4062 487);
DISPLAY INVISIBLE (4062 487);
FORCEPROP 2 LAST CDS_LIB mstr_symbols
J 0
(4050 475);
PAINT MONO (4050 475);
DISPLAY INVISIBLE (4050 475);
FORCEPROP 2 LAST PAGE_BORDER TRUE
J 0
(-3840 5725);
DISPLAY 0.638298 (-3840 5725);
PAINT PINK (-3840 5725);
DISPLAY INVISIBLE (-3840 5725);
FORCEPROP 2 LAST CDS_XR_PAGE_TITLE CR-187 : @BASEBOARD_FAB2_LIB.BASEBOARD_FAB2(SCH_1):PAGE187
J 0
(-3840 5725);
DISPLAY 0.638298 (-3840 5725);
PAINT PINK (-3840 5725);
DISPLAY INVISIBLE (-3840 5725);
WIRE 16 -1 (625 2250)(625 1950);
WIRE 16 -1 (625 2400)(625 2250);
WIRE 16 -1 (250 2250)(625 2250);
WIRE 16 -1 (625 2450)(625 2400);
WIRE 16 -1 (250 2400)(625 2400);
WIRE 16 -1 (625 2600)(625 2450);
WIRE 16 -1 (250 2450)(625 2450);
WIRE 16 -1 (625 2650)(625 2600);
WIRE 16 -1 (250 2600)(625 2600);
WIRE 16 -1 (625 2800)(625 2650);
WIRE 16 -1 (250 2650)(625 2650);
WIRE 16 -1 (625 2850)(625 2800);
WIRE 16 -1 (250 2800)(625 2800);
WIRE 16 -1 (625 2850)(625 3000);
WIRE 16 -1 (250 2850)(625 2850);
WIRE 16 -1 (625 3050)(625 3000);
WIRE 16 -1 (250 3000)(625 3000);
WIRE 16 -1 (625 3200)(625 3050);
WIRE 16 -1 (250 3050)(625 3050);
WIRE 16 -1 (625 3250)(625 3200);
WIRE 16 -1 (250 3200)(625 3200);
WIRE 16 -1 (625 3400)(625 3250);
WIRE 16 -1 (250 3250)(625 3250);
WIRE 16 -1 (625 3450)(625 3400);
WIRE 16 -1 (250 3400)(625 3400);
WIRE 16 -1 (625 3600)(625 3450);
WIRE 16 -1 (250 3450)(625 3450);
WIRE 16 -1 (625 3650)(625 3600);
WIRE 16 -1 (250 3600)(625 3600);
WIRE 16 -1 (625 3800)(625 3650);
WIRE 16 -1 (250 3650)(625 3650);
WIRE 16 -1 (625 3850)(625 3800);
WIRE 16 -1 (250 3800)(625 3800);
WIRE 16 -1 (625 4000)(625 3850);
WIRE 16 -1 (250 3850)(625 3850);
WIRE 16 -1 (250 4000)(625 4000);
WIRE 16 -1 (-725 2150)(-725 1900);
WIRE 16 -1 (-725 2300)(-725 2150);
WIRE 16 -1 (-350 2150)(-725 2150);
WIRE 16 -1 (-725 2350)(-725 2300);
WIRE 16 -1 (-350 2300)(-725 2300);
WIRE 16 -1 (-725 2500)(-725 2350);
WIRE 16 -1 (-350 2350)(-725 2350);
WIRE 16 -1 (-725 2550)(-725 2500);
WIRE 16 -1 (-350 2500)(-725 2500);
WIRE 16 -1 (-725 2700)(-725 2550);
WIRE 16 -1 (-350 2550)(-725 2550);
WIRE 16 -1 (-725 2750)(-725 2700);
WIRE 16 -1 (-350 2700)(-725 2700);
WIRE 16 -1 (-725 2750)(-725 2900);
WIRE 16 -1 (-350 2750)(-725 2750);
WIRE 16 -1 (-725 2950)(-725 2900);
WIRE 16 -1 (-350 2900)(-725 2900);
WIRE 16 -1 (-725 3100)(-725 2950);
WIRE 16 -1 (-350 2950)(-725 2950);
WIRE 16 -1 (-725 3150)(-725 3100);
WIRE 16 -1 (-725 3100)(-350 3100);
WIRE 16 -1 (-725 3300)(-725 3150);
WIRE 16 -1 (-350 3150)(-725 3150);
WIRE 16 -1 (-725 3350)(-725 3300);
WIRE 16 -1 (-350 3300)(-725 3300);
WIRE 16 -1 (-725 3500)(-725 3350);
WIRE 16 -1 (-350 3350)(-725 3350);
WIRE 16 -1 (-725 3550)(-725 3500);
WIRE 16 -1 (-350 3500)(-725 3500);
WIRE 16 -1 (-725 3700)(-725 3550);
WIRE 16 -1 (-350 3550)(-725 3550);
WIRE 16 -1 (-725 3750)(-725 3700);
WIRE 16 -1 (-350 3700)(-725 3700);
WIRE 16 -1 (-725 3900)(-725 3750);
WIRE 16 -1 (-350 3750)(-725 3750);
WIRE 16 -1 (-350 3900)(-725 3900);
WIRE 16 -1 (1950 4150)(1950 4200);
WIRE 16 -1 (1950 4850)(1950 4775);
WIRE 16 -1 (-1000 4050)(-1000 4325);
WIRE 16 -1 (-1000 4050)(-1000 4000);
WIRE 16 -1 (-350 4050)(-1000 4050);
WIRE 16 -1 (-350 4000)(-1000 4000);
WIRE 17 -1 (-2000 4025)(-3000 4025);
FORCEPROP 0 LAST SIG_NAME P3E_OCP_CPU0_PE3_C_TXN<7:0>
J 0
(-3000 4035);
DISPLAY 0.617021 (-3000 4035);
PAINT ORANGE (-3000 4035);
WIRE 17 -1 (-2000 4025)(-2000 3825);
WIRE 17 -1 (-2000 3825)(-2000 3625);
WIRE 17 -1 (-2000 3625)(-2000 3425);
WIRE 17 -1 (-2000 3425)(-2000 3225);
WIRE 17 -1 (-2000 3025)(-2000 3225);
WIRE 17 -1 (-2000 2825)(-2000 3025);
WIRE 17 -1 (-2000 2625)(-2000 2825);
WIRE 17 -1 (-2000 2425)(-2000 2625);
WIRE 17 -1 (1600 2575)(1600 2775);
WIRE 17 -1 (1600 2775)(1600 2975);
WIRE 17 -1 (1600 2975)(1600 3175);
WIRE 17 -1 (1600 3175)(1600 3325);
WIRE 17 -1 (1600 3525)(1600 3325);
WIRE 17 -1 (1600 3725)(1600 3525);
WIRE 17 -1 (1600 3975)(1600 3725);
WIRE 17 -1 (1600 4025)(2475 4025);
FORCEPROP 2 LAST SIG_NAME P3E_CPU0_PE3_OCP_RXP<7:0>
J 0
(1900 4033);
DISPLAY 0.617021 (1900 4033);
PAINT ORANGE (1900 4033);
WIRE 17 -1 (1600 4025)(1600 3975);
WIRE 17 -1 (1800 2525)(1800 2725);
WIRE 17 -1 (1800 2925)(1800 2725);
WIRE 17 -1 (1800 2925)(1800 3125);
WIRE 17 -1 (1800 3125)(1800 3375);
WIRE 17 -1 (1800 3575)(1800 3375);
WIRE 17 -1 (1800 3775)(1800 3575);
WIRE 17 -1 (1800 3925)(1800 3775);
WIRE 17 -1 (1800 3950)(2475 3950);
FORCEPROP 2 LAST SIG_NAME P3E_CPU0_PE3_OCP_RXN<7:0>
J 0
(1900 3973);
DISPLAY 0.617021 (1900 3973);
PAINT ORANGE (1900 3973);
WIRE 17 -1 (1800 3950)(1800 3925);
WIRE 17 -1 (-1725 4075)(-3000 4075);
FORCEPROP 0 LAST SIG_NAME P3E_OCP_CPU0_PE3_C_TXP<7:0>
J 0
(-3000 4085);
DISPLAY 0.617021 (-3000 4085);
PAINT ORANGE (-3000 4085);
WIRE 17 -1 (-1725 4075)(-1725 3875);
WIRE 17 -1 (-1725 3875)(-1725 3675);
WIRE 17 -1 (-1725 3675)(-1725 3475);
WIRE 17 -1 (-1725 3275)(-1725 3475);
WIRE 17 -1 (-1725 3075)(-1725 3275);
WIRE 17 -1 (-1725 3075)(-1725 2875);
WIRE 17 -1 (-1725 2475)(-1725 2675);
WIRE 17 -1 (-1725 2675)(-1725 2875);
WIRE 16 -1 (250 3700)(1500 3700);
WIRE 16 -1 (-1150 4775)(-1825 4775);
WIRE 16 -1 (-1150 5250)(-1150 4775);
WIRE 16 -1 (-450 4775)(-1150 4775);
WIRE 16 -1 (-1825 5250)(-1825 4775);
WIRE 16 -1 (-1150 5250)(-1825 5250);
WIRE 16 -1 (-1825 4775)(-2700 4775);
WIRE 16 -1 (-2700 5250)(-2700 4775);
WIRE 16 -1 (-1825 5250)(-2700 5250);
WIRE 16 -1 (-3550 4775)(-2700 4775);
WIRE 16 -1 (-3850 4775)(-3550 4775);
WIRE 16 -1 (200 4775)(-450 4775);
WIRE 16 -1 (-450 5250)(-1150 5250);
WIRE 16 -1 (-450 5250)(-450 4775);
WIRE 16 -1 (925 4775)(200 4775);
WIRE 16 -1 (925 4875)(925 4775);
WIRE 16 -1 (200 5250)(-450 5250);
WIRE 16 -1 (200 5250)(200 4775);
WIRE 16 -1 (-3850 4875)(-3850 4775);
WIRE 16 -1 (-3850 4875)(925 4875);
WIRE 16 -1 (-3550 5250)(-3550 4775);
WIRE 16 -1 (-3550 5250)(-2700 5250);
WIRE 16 -1 (-3850 5250)(-3550 5250);
WIRE 16 -1 (-3850 4975)(-3850 4875);
WIRE 16 -1 (925 5250)(200 5250);
WIRE 16 -1 (925 4875)(925 4975);
WIRE 16 -1 (-3850 4975)(925 4975);
WIRE 16 -1 (925 4975)(925 5075);
WIRE 16 -1 (925 5250)(925 5075);
WIRE 16 -1 (-3850 4975)(-3850 5075);
WIRE 16 -1 (-3850 5250)(-3850 5075);
WIRE 16 -1 (-3850 5075)(925 5075);
WIRE 16 -1 (250 3550)(1700 3550);
WIRE 3 2175 (-2150 2050)(-950 2050);
WIRE 3 2175 (-950 2150)(-950 2050);
WIRE 3 2175 (-2150 2150)(-2150 2050);
WIRE 3 2175 (-2150 2150)(-950 2150);
WIRE 16 -1 (250 2550)(1500 2550);
WIRE 16 -1 (250 2500)(1700 2500);
WIRE 16 -1 (250 2350)(1550 2350);
FORCEPROP 0 LAST SIG_NAME CLK_100M_MEZZ3_DP
J 1
(1263 2360);
DISPLAY 0.617021 (1263 2360);
PAINT ORANGE (1263 2360);
WIRE 16 -1 (250 2300)(1550 2300);
FORCEPROP 0 LAST SIG_NAME CLK_100M_MEZZ3_DN
J 1
(1263 2310);
DISPLAY 0.617021 (1263 2310);
PAINT ORANGE (1263 2310);
WIRE 16 -1 (250 2200)(2175 2200);
FORCEPROP 0 LAST SIG_NAME RST_PCIE_CPU_DEV1_R_N
J 1
(900 2210);
DISPLAY 0.617021 (900 2210);
PAINT ORANGE (900 2210);
FORCEPROP 2 LASTPROP $XRERR UNIQUE?
J 0
(660 2210);
DISPLAY 0.638298 (660 2210);
PAINT MONO (660 2210);
DISPLAY INVISIBLE (660 2210);
WIRE 16 -1 (250 2150)(1625 2150);
FORCEPROP 0 LAST SIG_NAME RST_PCIE_CPU_DEV2_R_N
J 1
(900 2160);
DISPLAY 0.617021 (900 2160);
PAINT ORANGE (900 2160);
FORCEPROP 2 LASTPROP $XRERR UNIQUE?
J 0
(660 2160);
DISPLAY 0.638298 (660 2160);
PAINT MONO (660 2160);
DISPLAY INVISIBLE (660 2160);
WIRE 16 -1 (250 2100)(1175 2100);
FORCEPROP 0 LAST SIG_NAME RST_PCIE_CPU_DEV3_R_N
J 1
(900 2110);
DISPLAY 0.617021 (900 2110);
PAINT ORANGE (900 2110);
FORCEPROP 2 LASTPROP $XRERR UNIQUE?
J 0
(660 2110);
DISPLAY 0.638298 (660 2110);
PAINT MONO (660 2110);
DISPLAY INVISIBLE (660 2110);
WIRE 16 -1 (250 2750)(1500 2750);
WIRE 16 -1 (250 2700)(1700 2700);
WIRE 16 -1 (-350 3400)(-1900 3400);
WIRE 3 2175 (1700 4075)(2250 4075);
WIRE 3 2175 (2250 5000)(2250 4075);
WIRE 3 2175 (1700 5000)(1700 4075);
WIRE 3 2175 (1700 5000)(2250 5000);
WIRE 16 -1 (250 4050)(1500 4050);
FORCEPROP 0 LAST SIG_NAME FM_MEZZB_PRSNT1_N
J 1
(563 4060);
DISPLAY 0.617021 (563 4060);
PAINT ORANGE (563 4060);
FORCEPROP 2 LASTPROP $XRERR UNIQUE?
J 0
(323 4060);
DISPLAY 0.638298 (323 4060);
PAINT MONO (323 4060);
DISPLAY INVISIBLE (323 4060);
WIRE 16 -1 (1500 4500)(1500 4050);
WIRE 16 -1 (1950 4500)(1500 4500);
WIRE 16 -1 (1950 4500)(1950 4450);
WIRE 16 -1 (1950 4575)(1950 4500);
WIRE 16 -1 (-350 3250)(-1625 3250);
WIRE 16 -1 (-350 3850)(-1625 3850);
WIRE 16 -1 (-350 3450)(-1625 3450);
WIRE 16 -1 (250 3500)(1500 3500);
WIRE 16 -1 (250 3350)(1700 3350);
WIRE 16 -1 (250 3300)(1500 3300);
WIRE 16 -1 (-1625 3050)(-350 3050);
WIRE 16 -1 (-350 3000)(-1900 3000);
WIRE 16 -1 (-1625 2850)(-350 2850);
WIRE 16 -1 (-350 2800)(-1900 2800);
WIRE 16 -1 (1375 2100)(2950 2100);
FORCEPROP 0 LAST SIG_NAME RST_PCIE_CPU_DEV3_N
J 1
(2700 2110);
DISPLAY 0.617021 (2700 2110);
PAINT ORANGE (2700 2110);
WIRE 16 -1 (250 2900)(1700 2900);
WIRE 16 -1 (1500 2950)(250 2950);
WIRE 16 -1 (-350 3650)(-1625 3650);
WIRE 16 -1 (-350 3600)(-1900 3600);
WIRE 16 -1 (-350 3800)(-1900 3800);
WIRE 16 -1 (-350 3950)(-875 3950);
FORCEPROP 0 LAST SIG_NAME TP_RSVD_B1
J 0
(-835 3960);
DISPLAY 0.617021 (-835 3960);
PAINT ORANGE (-835 3960);
FORCEPROP 2 LASTPROP $XRERR UNIQUE?
J 0
(-1115 3950);
DISPLAY 0.638298 (-1115 3950);
PAINT MONO (-1115 3950);
DISPLAY INVISIBLE (-1115 3950);
WIRE 16 -1 (1825 2150)(2950 2150);
FORCEPROP 0 LAST SIG_NAME RST_PCIE_CPU_DEV2_N
J 1
(2700 2160);
DISPLAY 0.617021 (2700 2160);
PAINT ORANGE (2700 2160);
WIRE 16 -1 (2375 2200)(2950 2200);
FORCEPROP 0 LAST SIG_NAME RST_PCIE_CPU_DEV1_N
J 1
(2700 2210);
DISPLAY 0.617021 (2700 2210);
PAINT ORANGE (2700 2210);
WIRE 16 -1 (250 3150)(1500 3150);
WIRE 16 -1 (250 3100)(1700 3100);
WIRE 16 -1 (-350 3200)(-1900 3200);
WIRE 16 -1 (-350 2100)(-1650 2100);
FORCEPROP 0 LAST SIG_NAME FM_OCP_MEZZB_PRES_N
J 1
(-1287 2110);
DISPLAY 0.617021 (-1287 2110);
PAINT ORANGE (-1287 2110);
WIRE 16 -1 (-350 2200)(-1650 2200);
FORCEPROP 0 LAST SIG_NAME CLK_100M_MEZZ4_DN
J 1
(-1412 2210);
DISPLAY 0.617021 (-1412 2210);
PAINT ORANGE (-1412 2210);
WIRE 16 -1 (-350 2250)(-1650 2250);
FORCEPROP 0 LAST SIG_NAME CLK_100M_MEZZ4_DP
J 1
(-1412 2260);
DISPLAY 0.617021 (-1412 2260);
PAINT ORANGE (-1412 2260);
WIRE 16 -1 (-350 2450)(-1625 2450);
WIRE 16 -1 (-350 2600)(-1900 2600);
WIRE 16 -1 (-350 2650)(-1625 2650);
WIRE 16 -1 (250 3750)(1700 3750);
WIRE 16 -1 (250 3900)(1700 3900);
WIRE 16 -1 (250 3950)(1500 3950);
WIRE 16 -1 (-350 2400)(-1900 2400);
DOT 1 (-725 2300);
DOT 1 (-725 2350);
DOT 1 (-725 2500);
DOT 1 (625 3200);
DOT 1 (-725 3150);
DOT 1 (-725 3100);
DOT 1 (925 4975);
DOT 1 (-3850 4975);
DOT 1 (-3850 4875);
DOT 1 (-3550 4775);
DOT 1 (-2700 4775);
DOT 1 (-3850 5075);
DOT 1 (-3550 5250);
DOT 1 (-2700 5250);
DOT 1 (-1825 4775);
DOT 1 (-1150 4775);
DOT 1 (-450 4775);
DOT 1 (-1825 5250);
DOT 1 (-1150 5250);
DOT 1 (-450 5250);
DOT 1 (200 4775);
DOT 1 (925 5075);
DOT 1 (200 5250);
DOT 1 (-725 2150);
DOT 1 (-725 2550);
DOT 1 (-725 2700);
DOT 1 (-725 2750);
DOT 1 (-725 2900);
DOT 1 (-725 3500);
DOT 1 (-1000 4050);
DOT 1 (-725 3750);
DOT 1 (-725 3550);
DOT 1 (-725 3300);
DOT 1 (-725 3350);
DOT 1 (625 3050);
DOT 1 (625 2450);
DOT 1 (625 2400);
DOT 1 (625 3000);
DOT 1 (625 2850);
DOT 1 (625 2800);
DOT 1 (625 2650);
DOT 1 (625 2600);
DOT 1 (625 3850);
DOT 1 (625 3250);
DOT 1 (625 3450);
DOT 1 (625 3600);
DOT 1 (625 3800);
DOT 1 (-725 2950);
DOT 1 (625 3650);
DOT 1 (625 2250);
DOT 1 (-725 3700);
DOT 1 (925 4875);
DOT 1 (625 3400);
DOT 1 (1950 4500);
FORCENOTE
FCI PLUG # ON OCP MEZZ
(-3500 5175) 0;
DISPLAY LEFT (-3500 5175);
DISPLAY 1.021277 (-3500 5175);
PAINT PURPLE (-3500 5175);
FORCENOTE
A28699-020
(225 5000) 0;
DISPLAY LEFT (225 5000);
DISPLAY 1.021277 (225 5000);
PAINT PURPLE (225 5000);
FORCENOTE
TP FAB1  ADD R2W1 10K OHM AND CHANGE R2B8 TO 887 OHM1210
(1431 5047) 0;
DISPLAY LEFT (1431 5047);
DISPLAY 1.021277 (1431 5047);
PAINT RED (1431 5047);
FORCENOTE
10135584-644402LF
(-2650 4800) 0;
DISPLAY LEFT (-2650 4800);
DISPLAY 1.021277 (-2650 4800);
PAINT PURPLE (-2650 4800);
FORCENOTE
0.26V~0.27V
(2045 4470) 0;
DISPLAY LEFT (2045 4470);
DISPLAY 1.021277 (2045 4470);
PAINT PURPLE (2045 4470);
FORCENOTE
B (80P)
(-3825 4900) 0;
DISPLAY LEFT (-3825 4900);
DISPLAY 1.021277 (-3825 4900);
PAINT PURPLE (-3825 4900);
FORCENOTE
(5/8MM STACK)
(-1100 5100) 0;
DISPLAY LEFT (-1100 5100);
DISPLAY 1.021277 (-1100 5100);
PAINT PURPLE (-1100 5100);
FORCENOTE
A (120P)
(-3825 5000) 0;
DISPLAY LEFT (-3825 5000);
DISPLAY 1.021277 (-3825 5000);
PAINT PURPLE (-3825 5000);
FORCENOTE
MATED HT CONNECTOR P/NS
(-3825 5275) 0;
DISPLAY LEFT (-3825 5275);
DISPLAY 1.021277 (-3825 5275);
PAINT PURPLE (-3825 5275);
FORCENOTE
FROM CPU0
(-3100 3825) 0;
DISPLAY LEFT (-3100 3825);
DISPLAY 1.021277 (-3100 3825);
PAINT PURPLE (-3100 3825);
FORCENOTE
CONN
(-3825 5175) 0;
DISPLAY LEFT (-3825 5175);
DISPLAY 1.021277 (-3825 5175);
PAINT PURPLE (-3825 5175);
FORCENOTE
(8/12 MM STACK)
(-2650 5100) 0;
DISPLAY LEFT (-2650 5100);
DISPLAY 1.021277 (-2650 5100);
PAINT PURPLE (-2650 5100);
FORCENOTE
FCI PLUG # ON OCP MEZZ
(-2650 5175) 0;
DISPLAY LEFT (-2650 5175);
DISPLAY 1.021277 (-2650 5175);
PAINT PURPLE (-2650 5175);
FORCENOTE
61083-124402LF
(-2650 5000) 0;
DISPLAY LEFT (-2650 5000);
DISPLAY 1.021277 (-2650 5000);
PAINT PURPLE (-2650 5000);
FORCENOTE
61082-081402LF
(-1775 4900) 0;
DISPLAY LEFT (-1775 4900);
DISPLAY 1.021277 (-1775 4900);
PAINT PURPLE (-1775 4900);
FORCENOTE
(5/8MM STACK)
(-1775 5100) 0;
DISPLAY LEFT (-1775 5100);
DISPLAY 1.021277 (-1775 5100);
PAINT PURPLE (-1775 5100);
FORCENOTE
E67482-006
(-1100 4900) 0;
DISPLAY LEFT (-1100 4900);
DISPLAY 1.021277 (-1100 4900);
PAINT PURPLE (-1100 4900);
FORCENOTE
A28699-010
(-1100 5000) 0;
DISPLAY LEFT (-1100 5000);
DISPLAY 1.021277 (-1100 5000);
PAINT PURPLE (-1100 5000);
FORCENOTE
FCI RECPT IPN ON CC
(-1125 5175) 0;
DISPLAY LEFT (-1125 5175);
DISPLAY 1.021277 (-1125 5175);
PAINT PURPLE (-1125 5175);
FORCENOTE
FCI RECPT # ON CC
(-1775 5175) 0;
DISPLAY LEFT (-1775 5175);
DISPLAY 1.021277 (-1775 5175);
PAINT PURPLE (-1775 5175);
FORCENOTE
10135583-641402LF
(-1775 4800) 0;
DISPLAY LEFT (-1775 4800);
DISPLAY 1.021277 (-1775 4800);
PAINT PURPLE (-1775 4800);
FORCENOTE
(12MM STACK)
(-425 5100) 0;
DISPLAY LEFT (-425 5100);
DISPLAY 1.021277 (-425 5100);
PAINT PURPLE (-425 5100);
FORCENOTE
61082-122402LF
(-425 5000) 0;
DISPLAY LEFT (-425 5000);
DISPLAY 1.021277 (-425 5000);
PAINT PURPLE (-425 5000);
FORCENOTE
FCI RECPT # ON CC
(-425 5175) 0;
DISPLAY LEFT (-425 5175);
DISPLAY 1.021277 (-425 5175);
PAINT PURPLE (-425 5175);
FORCENOTE
61082-082402LF
(-425 4900) 0;
DISPLAY LEFT (-425 4900);
DISPLAY 1.021277 (-425 4900);
PAINT PURPLE (-425 4900);
FORCENOTE
10135583-642402LF
(-425 4800) 0;
DISPLAY LEFT (-425 4800);
DISPLAY 1.021277 (-425 4800);
PAINT PURPLE (-425 4800);
FORCENOTE
H87568-002
(225 4800) 0;
DISPLAY LEFT (225 4800);
DISPLAY 1.021277 (225 4800);
PAINT PURPLE (225 4800);
FORCENOTE
(12 MM STACK)
(225 5100) 0;
DISPLAY LEFT (225 5100);
DISPLAY 1.021277 (225 5100);
PAINT PURPLE (225 5100);
FORCENOTE
FCI RECPT IPN ON CC
(225 5175) 0;
DISPLAY LEFT (225 5175);
DISPLAY 1.021277 (225 5175);
PAINT PURPLE (225 5175);
FORCENOTE
E67482-008
(225 4900) 0;
DISPLAY LEFT (225 4900);
DISPLAY 1.021277 (225 4900);
PAINT PURPLE (225 4900);
FORCENOTE
TP FAB1 RENAME 1218
(-2125 1975) 0;
DISPLAY LEFT (-2125 1975);
DISPLAY 1.021277 (-2125 1975);
PAINT RED (-2125 1975);
FORCENOTE
TP FAB1 RENAME 1218
(2350 4950) 0;
DISPLAY LEFT (2350 4950);
DISPLAY 1.021277 (2350 4950);
PAINT RED (2350 4950);
FORCENOTE
61083-121402LF
(-3500 5000) 0;
DISPLAY LEFT (-3500 5000);
DISPLAY 1.021277 (-3500 5000);
PAINT PURPLE (-3500 5000);
FORCENOTE
61082-121402LF
(-1775 5000) 0;
DISPLAY LEFT (-1775 5000);
DISPLAY 1.021277 (-1775 5000);
PAINT PURPLE (-1775 5000);
FORCENOTE
TO CPU0
(2350 3825) 0;
DISPLAY LEFT (2350 3825);
DISPLAY 1.021277 (2350 3825);
PAINT PURPLE (2350 3825);
FORCENOTE
10135584-641402LF
(-3500 4800) 0;
DISPLAY LEFT (-3500 4800);
DISPLAY 1.021277 (-3500 4800);
PAINT PURPLE (-3500 4800);
FORCENOTE
61082-081402LF
(-3500 4900) 0;
DISPLAY LEFT (-3500 4900);
DISPLAY 1.021277 (-3500 4900);
PAINT PURPLE (-3500 4900);
FORCENOTE
H87568-001
(-1100 4800) 0;
DISPLAY LEFT (-1100 4800);
DISPLAY 1.021277 (-1100 4800);
PAINT PURPLE (-1100 4800);
FORCENOTE
61083-084402LF
(-2650 4900) 0;
DISPLAY LEFT (-2650 4900);
DISPLAY 1.021277 (-2650 4900);
PAINT PURPLE (-2650 4900);
FORCENOTE
C (64P)
(-3825 4800) 0;
DISPLAY LEFT (-3825 4800);
DISPLAY 1.021277 (-3825 4800);
PAINT PURPLE (-3825 4800);
FORCENOTE
(5MM STACK)
(-3500 5100) 0;
DISPLAY LEFT (-3500 5100);
DISPLAY 1.021277 (-3500 5100);
PAINT PURPLE (-3500 5100);
QUIT
